FILE_TYPE = MACRO_DRAWING;
SET COLOR_WIRE YELLOW;
SET COLOR_PROP MONO;
SET COLOR_DOT WHITE;
SET COLOR_ARC YELLOW;
SET COLOR_BODY GREEN;
SET COLOR_NOTE MONO;
SET PROP_DISPLAY VALUE;
SET PAGE_NUMBER P141;
FORCEADD CAP..2
(-3150 4375);
FORCEPROP 1 LAST LOCATION C9G12
J 1
(-3600 4375);
DISPLAY 0.617021 (-3600 4375);
PAINT AQUA (-3600 4375);
FORCEPROP 1 LAST PART_NUMBER A36096-066
J 1
(-3450 4375);
DISPLAY 0.617021 (-3450 4375);
PAINT BLUE (-3450 4375);
FORCEPROP 1 LAST VALUE 4700PF
J 2
(-3175 4375);
DISPLAY 0.617021 (-3175 4375);
PAINT SKYBLUE (-3175 4375);
FORCEPROP 1 LAST MATERIAL EMPTY
J 0
(-3075 4375);
DISPLAY 0.617021 (-3075 4375);
PAINT RED (-3075 4375);
FORCEPROP 1 LAST TOLERANCE 10%
J 2
(-2900 4375);
DISPLAY 0.617021 (-2900 4375);
PAINT SKYBLUE (-2900 4375);
FORCEPROP 2 LAST CDS_LOCATION C9G12
J 1
(-3600 4375);
DISPLAY 0.617021 (-3600 4375);
PAINT AQUA (-3600 4375);
DISPLAY INVISIBLE (-3600 4375);
FORCEPROP 1 LASTPIN (-3250 4375) $PN 1
J 0
(-3260 4390);
DISPLAY 0.787234 (-3260 4390);
PAINT ORANGE (-3260 4390);
DISPLAY INVISIBLE (-3260 4390);
FORCEPROP 2 LAST CDS_LIB mstr_discrete
J 0
(-3150 4375);
PAINT MONO (-3150 4375);
DISPLAY INVISIBLE (-3150 4375);
FORCEPROP 1 LAST VOLTAGE 50V
J 0
(-3075 4375);
DISPLAY 0.617021 (-3075 4375);
PAINT SKYBLUE (-3075 4375);
DISPLAY INVISIBLE (-3075 4375);
FORCEPROP 1 LAST PATH I100
J 0
(-3150 4575);
DISPLAY 0.978723 (-3150 4575);
PAINT WHITE (-3150 4575);
DISPLAY INVISIBLE (-3150 4575);
FORCEPROP 2 LAST CDS_SEC 1
J 0
(-3150 4625);
PAINT MONO (-3150 4625);
DISPLAY INVISIBLE (-3150 4625);
FORCEPROP 2 LAST $SEC 1
J 0
(-3150 4625);
PAINT MONO (-3150 4625);
DISPLAY INVISIBLE (-3150 4625);
FORCEPROP 2 LAST NO_XNET_CONNECTION 1
J 0
(-3150 4625);
PAINT MONO (-3150 4625);
DISPLAY INVISIBLE (-3150 4625);
FORCEPROP 1 LASTPIN (-3050 4375) $PN 2
J 0
(-3065 4390);
DISPLAY 0.787234 (-3065 4390);
PAINT ORANGE (-3065 4390);
DISPLAY INVISIBLE (-3065 4390);
FORCEPROP 1 LAST PACK_TYPE 0402LF
J 1
(-2900 4375);
DISPLAY 0.617021 (-2900 4375);
PAINT SKYBLUE (-2900 4375);
DISPLAY INVISIBLE (-2900 4375);
FORCEPROP 2 LAST ROOM NIC_SPRV
J 0
(-2900 4425);
DISPLAY 1.021277 (-2900 4425);
PAINT ORANGE (-2900 4425);
DISPLAY INVISIBLE (-2900 4425);
FORCEPROP 2 LAST BOM_COST NT_GBE_BASE
J 0
(-2900 4475);
DISPLAY 1.021277 (-2900 4475);
PAINT ORANGE (-2900 4475);
DISPLAY INVISIBLE (-2900 4475);
FORCEADD CAP..2
(-2825 4075);
FORCEPROP 1 LAST MATERIAL EMPTY
J 0
(-2750 4075);
DISPLAY 0.617021 (-2750 4075);
PAINT RED (-2750 4075);
FORCEPROP 1 LAST LOCATION C9G16
J 1
(-3275 4075);
DISPLAY 0.617021 (-3275 4075);
PAINT AQUA (-3275 4075);
FORCEPROP 1 LAST PART_NUMBER A36096-066
J 1
(-3125 4075);
DISPLAY 0.617021 (-3125 4075);
PAINT BLUE (-3125 4075);
FORCEPROP 1 LAST VALUE 4700PF
J 2
(-2850 4075);
DISPLAY 0.617021 (-2850 4075);
PAINT SKYBLUE (-2850 4075);
FORCEPROP 1 LAST TOLERANCE 10%
J 2
(-2575 4075);
DISPLAY 0.617021 (-2575 4075);
PAINT SKYBLUE (-2575 4075);
FORCEPROP 1 LAST PACK_TYPE 0402LF
J 1
(-2575 4075);
DISPLAY 0.617021 (-2575 4075);
PAINT SKYBLUE (-2575 4075);
DISPLAY INVISIBLE (-2575 4075);
FORCEPROP 1 LAST VOLTAGE 50V
J 0
(-2750 4075);
DISPLAY 0.617021 (-2750 4075);
PAINT SKYBLUE (-2750 4075);
DISPLAY INVISIBLE (-2750 4075);
FORCEPROP 2 LAST CDS_LIB mstr_discrete
J 0
(-2825 4075);
PAINT MONO (-2825 4075);
DISPLAY INVISIBLE (-2825 4075);
FORCEPROP 2 LAST CDS_LOCATION C9G16
J 1
(-3275 4075);
DISPLAY 0.617021 (-3275 4075);
PAINT AQUA (-3275 4075);
DISPLAY INVISIBLE (-3275 4075);
FORCEPROP 1 LASTPIN (-2725 4075) $PN 2
J 0
(-2740 4090);
DISPLAY 0.787234 (-2740 4090);
PAINT ORANGE (-2740 4090);
DISPLAY INVISIBLE (-2740 4090);
FORCEPROP 1 LASTPIN (-2925 4075) $PN 1
J 0
(-2935 4090);
DISPLAY 0.787234 (-2935 4090);
PAINT ORANGE (-2935 4090);
DISPLAY INVISIBLE (-2935 4090);
FORCEPROP 1 LAST PATH I101
J 0
(-2825 4275);
DISPLAY 0.978723 (-2825 4275);
PAINT WHITE (-2825 4275);
DISPLAY INVISIBLE (-2825 4275);
FORCEPROP 2 LAST CDS_SEC 1
J 0
(-2825 4325);
PAINT MONO (-2825 4325);
DISPLAY INVISIBLE (-2825 4325);
FORCEPROP 2 LAST $SEC 1
J 0
(-2825 4325);
PAINT MONO (-2825 4325);
DISPLAY INVISIBLE (-2825 4325);
FORCEPROP 2 LAST NO_XNET_CONNECTION 1
J 0
(-2825 4325);
PAINT MONO (-2825 4325);
DISPLAY INVISIBLE (-2825 4325);
FORCEPROP 2 LAST BOM_COST NT_GBE_BASE
J 0
(-2575 4175);
DISPLAY 1.021277 (-2575 4175);
PAINT ORANGE (-2575 4175);
DISPLAY INVISIBLE (-2575 4175);
FORCEPROP 2 LAST ROOM NIC_SPRV
J 0
(-2575 4125);
DISPLAY 1.021277 (-2575 4125);
PAINT ORANGE (-2575 4125);
DISPLAY INVISIBLE (-2575 4125);
FORCEADD CAP..2
(-3100 4025);
FORCEPROP 1 LAST LOCATION C9G13
J 1
(-3550 4025);
DISPLAY 0.617021 (-3550 4025);
PAINT AQUA (-3550 4025);
FORCEPROP 1 LAST PART_NUMBER A36096-066
J 1
(-3400 4025);
DISPLAY 0.617021 (-3400 4025);
PAINT BLUE (-3400 4025);
FORCEPROP 1 LAST VALUE 4700PF
J 2
(-3125 4025);
DISPLAY 0.617021 (-3125 4025);
PAINT SKYBLUE (-3125 4025);
FORCEPROP 1 LAST MATERIAL EMPTY
J 0
(-3025 4025);
DISPLAY 0.617021 (-3025 4025);
PAINT RED (-3025 4025);
FORCEPROP 1 LAST TOLERANCE 10%
J 2
(-2850 4025);
DISPLAY 0.617021 (-2850 4025);
PAINT SKYBLUE (-2850 4025);
FORCEPROP 2 LAST CDS_LOCATION C9G13
J 1
(-3550 4025);
DISPLAY 0.617021 (-3550 4025);
PAINT AQUA (-3550 4025);
DISPLAY INVISIBLE (-3550 4025);
FORCEPROP 1 LASTPIN (-3200 4025) $PN 1
J 0
(-3210 4040);
DISPLAY 0.787234 (-3210 4040);
PAINT ORANGE (-3210 4040);
DISPLAY INVISIBLE (-3210 4040);
FORCEPROP 2 LAST CDS_LIB mstr_discrete
J 0
(-3100 4025);
PAINT MONO (-3100 4025);
DISPLAY INVISIBLE (-3100 4025);
FORCEPROP 1 LAST VOLTAGE 50V
J 0
(-3025 4025);
DISPLAY 0.617021 (-3025 4025);
PAINT SKYBLUE (-3025 4025);
DISPLAY INVISIBLE (-3025 4025);
FORCEPROP 1 LASTPIN (-3000 4025) $PN 2
J 0
(-3015 4040);
DISPLAY 0.787234 (-3015 4040);
PAINT ORANGE (-3015 4040);
DISPLAY INVISIBLE (-3015 4040);
FORCEPROP 1 LAST PACK_TYPE 0402LF
J 1
(-2850 4025);
DISPLAY 0.617021 (-2850 4025);
PAINT SKYBLUE (-2850 4025);
DISPLAY INVISIBLE (-2850 4025);
FORCEPROP 2 LAST ROOM NIC_SPRV
J 0
(-2850 4075);
DISPLAY 1.021277 (-2850 4075);
PAINT ORANGE (-2850 4075);
DISPLAY INVISIBLE (-2850 4075);
FORCEPROP 2 LAST CDS_SEC 1
J 0
(-3100 4275);
PAINT MONO (-3100 4275);
DISPLAY INVISIBLE (-3100 4275);
FORCEPROP 2 LAST $SEC 1
J 0
(-3100 4275);
PAINT MONO (-3100 4275);
DISPLAY INVISIBLE (-3100 4275);
FORCEPROP 2 LAST NO_XNET_CONNECTION 1
J 0
(-3100 4275);
PAINT MONO (-3100 4275);
DISPLAY INVISIBLE (-3100 4275);
FORCEPROP 1 LAST PATH I102
J 0
(-3100 4225);
DISPLAY 0.978723 (-3100 4225);
PAINT WHITE (-3100 4225);
DISPLAY INVISIBLE (-3100 4225);
FORCEPROP 2 LAST BOM_COST NT_GBE_BASE
J 0
(-2850 4125);
DISPLAY 1.021277 (-2850 4125);
PAINT ORANGE (-2850 4125);
DISPLAY INVISIBLE (-2850 4125);
FORCEADD OFFPAGE..4
(-2000 4425);
FORCEPROP 2 LAST $XR0 181 
J 0
(-1814 4425);
DISPLAY 0.638298 (-1814 4425);
PAINT MONO (-1814 4425);
FORCEPROP 1 LAST COMMENT_BODY TRUE
J 0
(-2025 4325);
DISPLAY 0.872340 (-2025 4325);
PAINT GREEN (-2025 4325);
DISPLAY INVISIBLE (-2025 4325);
FORCEPROP 2 LAST CDS_LIB mstr_standard
J 0
(-2000 4425);
PAINT MONO (-2000 4425);
DISPLAY INVISIBLE (-2000 4425);
FORCEPROP 2 LAST PATH I103
J 0
(-1950 4500);
DISPLAY 1.021277 (-1950 4500);
PAINT ORANGE (-1950 4500);
DISPLAY INVISIBLE (-1950 4500);
FORCEPROP 1 LAST OFFPAGE TRUE
J 0
(-1675 4300);
DISPLAY 0.872340 (-1675 4300);
PAINT GREEN (-1675 4300);
DISPLAY INVISIBLE (-1675 4300);
FORCEADD OFFPAGE..2
(-1950 4075);
FORCEPROP 2 LAST $XR0 181 
J 0
(-1761 4075);
DISPLAY 0.638298 (-1761 4075);
PAINT MONO (-1761 4075);
FORCEPROP 1 LAST COMMENT_BODY TRUE
J 0
(-1995 3980);
DISPLAY 0.872340 (-1995 3980);
PAINT GREEN (-1995 3980);
DISPLAY INVISIBLE (-1995 3980);
FORCEPROP 1 LAST OFFPAGE TRUE
J 0
(-1625 3950);
DISPLAY 0.872340 (-1625 3950);
PAINT GREEN (-1625 3950);
DISPLAY INVISIBLE (-1625 3950);
FORCEPROP 2 LAST CDS_LIB mstr_standard
J 0
(-1950 4075);
PAINT MONO (-1950 4075);
DISPLAY INVISIBLE (-1950 4075);
FORCEPROP 2 LAST PATH I104
J 0
(-1900 4150);
DISPLAY 1.021277 (-1900 4150);
PAINT ORANGE (-1900 4150);
DISPLAY INVISIBLE (-1900 4150);
FORCEADD OFFPAGE..4
(-2000 4375);
FORCEPROP 2 LAST $XR0 181 
J 0
(-1814 4375);
DISPLAY 0.638298 (-1814 4375);
PAINT MONO (-1814 4375);
FORCEPROP 1 LAST COMMENT_BODY TRUE
J 0
(-2025 4275);
DISPLAY 0.872340 (-2025 4275);
PAINT GREEN (-2025 4275);
DISPLAY INVISIBLE (-2025 4275);
FORCEPROP 2 LAST CDS_LIB mstr_standard
J 0
(-2000 4375);
PAINT MONO (-2000 4375);
DISPLAY INVISIBLE (-2000 4375);
FORCEPROP 2 LAST PATH I105
J 0
(-1825 4450);
DISPLAY 1.021277 (-1825 4450);
PAINT ORANGE (-1825 4450);
DISPLAY INVISIBLE (-1825 4450);
FORCEPROP 1 LAST OFFPAGE TRUE
J 0
(-1675 4250);
DISPLAY 0.872340 (-1675 4250);
PAINT GREEN (-1675 4250);
DISPLAY INVISIBLE (-1675 4250);
FORCEADD OFFPAGE..2
(-1950 4025);
FORCEPROP 2 LAST $XR0 181 
J 0
(-1761 4025);
DISPLAY 0.638298 (-1761 4025);
PAINT MONO (-1761 4025);
FORCEPROP 2 LAST CDS_LIB mstr_standard
J 0
(-1950 4025);
PAINT MONO (-1950 4025);
DISPLAY INVISIBLE (-1950 4025);
FORCEPROP 1 LAST COMMENT_BODY TRUE
J 0
(-1995 3930);
DISPLAY 0.872340 (-1995 3930);
PAINT GREEN (-1995 3930);
DISPLAY INVISIBLE (-1995 3930);
FORCEPROP 1 LAST OFFPAGE TRUE
J 0
(-1625 3900);
DISPLAY 0.872340 (-1625 3900);
PAINT GREEN (-1625 3900);
DISPLAY INVISIBLE (-1625 3900);
FORCEPROP 2 LAST PATH I106
J 0
(-1775 4100);
DISPLAY 1.021277 (-1775 4100);
PAINT ORANGE (-1775 4100);
DISPLAY INVISIBLE (-1775 4100);
FORCEADD GND_NIC..1
(-4175 1700);
FORCEPROP 3 LASTPIN (-4175 1750) SIG_NAME GND_NIC\g
J 0
(-4165 1760);
DISPLAY 0.659574 (-4165 1760);
PAINT MONO (-4165 1760);
DISPLAY INVISIBLE (-4165 1760);
FORCEPROP 1 LAST HDL_POWER GND_NIC
J 1
(-4150 1625);
DISPLAY 0.617021 (-4150 1625);
PAINT GREEN (-4150 1625);
FORCEPROP 1 LAST BODY_TYPE PLUMBING
J 0
(-4220 1657);
DISPLAY 0.340426 (-4220 1657);
PAINT GREEN (-4220 1657);
DISPLAY INVISIBLE (-4220 1657);
FORCEPROP 2 LAST CDS_LIB mstr_symbols
J 0
(-4175 1700);
PAINT MONO (-4175 1700);
DISPLAY INVISIBLE (-4175 1700);
FORCEPROP 1 LAST VOLTAGE 0.0V
J 0
(-4220 1657);
DISPLAY 0.340426 (-4220 1657);
PAINT SKYBLUE (-4220 1657);
DISPLAY INVISIBLE (-4220 1657);
FORCEPROP 1 LAST PATH I107
J 0
(-4100 1700);
DISPLAY 0.872340 (-4100 1700);
PAINT AQUA (-4100 1700);
DISPLAY INVISIBLE (-4100 1700);
FORCEADD GND_NIC..1
(-3000 1700);
FORCEPROP 3 LASTPIN (-3000 1750) SIG_NAME GND_NIC\g
J 0
(-2990 1760);
DISPLAY 0.659574 (-2990 1760);
PAINT MONO (-2990 1760);
DISPLAY INVISIBLE (-2990 1760);
FORCEPROP 1 LAST HDL_POWER GND_NIC
J 1
(-2975 1625);
DISPLAY 0.617021 (-2975 1625);
PAINT GREEN (-2975 1625);
FORCEPROP 1 LAST PATH I108
J 0
(-2925 1700);
DISPLAY 0.872340 (-2925 1700);
PAINT AQUA (-2925 1700);
DISPLAY INVISIBLE (-2925 1700);
FORCEPROP 1 LAST BODY_TYPE PLUMBING
J 0
(-3045 1657);
DISPLAY 0.340426 (-3045 1657);
PAINT GREEN (-3045 1657);
DISPLAY INVISIBLE (-3045 1657);
FORCEPROP 2 LAST CDS_LIB mstr_symbols
J 0
(-3000 1700);
PAINT MONO (-3000 1700);
DISPLAY INVISIBLE (-3000 1700);
FORCEPROP 1 LAST VOLTAGE 0.0V
J 0
(-3045 1657);
DISPLAY 0.340426 (-3045 1657);
PAINT SKYBLUE (-3045 1657);
DISPLAY INVISIBLE (-3045 1657);
FORCEADD CONN17_H71061002..1
(-3575 2500);
FORCEPROP 2 LASTPIN (-4025 2850) $PN R11
J 2
(-4035 2860);
DISPLAY 0.617021 (-4035 2860);
PAINT MONO (-4035 2860);
FORCEPROP 2 LASTPIN (-4025 2750) $PN R10
J 2
(-4035 2760);
DISPLAY 0.617021 (-4035 2760);
PAINT MONO (-4035 2760);
FORCEPROP 2 LASTPIN (-4025 2800) $PN R12
J 2
(-4035 2810);
DISPLAY 0.617021 (-4035 2810);
PAINT MONO (-4035 2810);
FORCEPROP 2 LASTPIN (-4025 2000) $PN MH1
J 2
(-4035 2010);
DISPLAY 0.617021 (-4035 2010);
PAINT MONO (-4035 2010);
FORCEPROP 1 LAST PART_NUMBER H71061-002
J 0
(-3975 1900);
DISPLAY 0.617021 (-3975 1900);
PAINT BLUE (-3975 1900);
FORCEPROP 2 LASTPIN (-3125 2000) $PN MH2
J 0
(-3115 2010);
DISPLAY 0.617021 (-3115 2010);
PAINT MONO (-3115 2010);
FORCEPROP 2 LASTPIN (-4025 2350) $PN L2
J 2
(-4035 2360);
DISPLAY 0.617021 (-4035 2360);
PAINT MONO (-4035 2360);
FORCEPROP 2 LASTPIN (-4025 2150) $PN L5
J 2
(-4035 2160);
DISPLAY 0.617021 (-4035 2160);
PAINT MONO (-4035 2160);
FORCEPROP 2 LASTPIN (-4025 2550) $PN R5
J 2
(-4035 2560);
DISPLAY 0.617021 (-4035 2560);
PAINT MONO (-4035 2560);
FORCEPROP 2 LASTPIN (-4025 2650) $PN R4
J 2
(-4035 2660);
DISPLAY 0.617021 (-4035 2660);
PAINT MONO (-4035 2660);
FORCEPROP 2 LASTPIN (-4025 2600) $PN R6
J 2
(-4035 2610);
DISPLAY 0.617021 (-4035 2610);
PAINT MONO (-4035 2610);
FORCEPROP 1 LAST MATERIAL CONN
J 0
(-3975 3100);
DISPLAY 0.617021 (-3975 3100);
PAINT SKYBLUE (-3975 3100);
FORCEPROP 1 LAST LOCATION JA9G1
J 0
(-3975 3150);
DISPLAY 0.617021 (-3975 3150);
PAINT AQUA (-3975 3150);
FORCEPROP 2 LASTPIN (-3125 2650) $PN R8
J 0
(-3115 2660);
DISPLAY 0.617021 (-3115 2660);
PAINT MONO (-3115 2660);
FORCEPROP 2 LASTPIN (-3125 2550) $PN R9
J 0
(-3115 2560);
DISPLAY 0.617021 (-3115 2560);
PAINT MONO (-3115 2560);
FORCEPROP 2 LASTPIN (-3125 2850) $PN R3
J 0
(-3115 2860);
DISPLAY 0.617021 (-3115 2860);
PAINT MONO (-3115 2860);
FORCEPROP 2 LASTPIN (-3125 2750) $PN R2
J 0
(-3115 2760);
DISPLAY 0.617021 (-3115 2760);
PAINT MONO (-3115 2760);
FORCEPROP 2 LASTPIN (-3125 2600) $PN R7
J 0
(-3115 2610);
DISPLAY 0.617021 (-3115 2610);
PAINT MONO (-3115 2610);
FORCEPROP 2 LASTPIN (-3125 2800) $PN R1
J 0
(-3115 2810);
DISPLAY 0.617021 (-3115 2810);
PAINT MONO (-3115 2810);
FORCEPROP 2 LASTPIN (-3125 2100) $PN L4
J 0
(-3115 2110);
DISPLAY 0.617021 (-3115 2110);
PAINT MONO (-3115 2110);
FORCEPROP 2 LASTPIN (-3125 2300) $PN L3
J 0
(-3115 2310);
DISPLAY 0.617021 (-3115 2310);
PAINT MONO (-3115 2310);
FORCEPROP 2 LASTPIN (-3125 2400) $PN L1
J 0
(-3115 2410);
DISPLAY 0.617021 (-3115 2410);
PAINT MONO (-3115 2410);
FORCEPROP 1 LAST CDS_LMAN_SYM_OUTLINE -400,550,400,-550
J 0
(-3575 2500);
DISPLAY 0.468085 (-3575 2500);
PAINT GREEN (-3575 2500);
DISPLAY INVISIBLE (-3575 2500);
FORCEPROP 2 LAST CDS_LIB mstr_conn
J 0
(-3575 2500);
PAINT ORANGE (-3575 2500);
DISPLAY INVISIBLE (-3575 2500);
FORCEPROP 1 LAST PACK_TYPE PIP1
J 0
(-3975 3200);
PAINT SKYBLUE (-3975 3200);
DISPLAY INVISIBLE (-3975 3200);
FORCEPROP 0 LAST BOM_COST NT_GBE_BASE
J 0
(-3975 3350);
DISPLAY 1.021277 (-3975 3350);
PAINT ORANGE (-3975 3350);
DISPLAY INVISIBLE (-3975 3350);
FORCEPROP 2 LAST CDS_SEC 1
J 0
(-3975 3200);
PAINT MONO (-3975 3200);
DISPLAY INVISIBLE (-3975 3200);
FORCEPROP 2 LAST $SEC 1
J 0
(-3975 3200);
PAINT MONO (-3975 3200);
DISPLAY INVISIBLE (-3975 3200);
FORCEPROP 2 LAST CDS_LOCATION JA9G1
J 0
(-3975 3150);
DISPLAY 0.617021 (-3975 3150);
PAINT AQUA (-3975 3150);
DISPLAY INVISIBLE (-3975 3150);
FORCEPROP 0 LAST ROOM NIC_SPRV
J 0
(-3975 3250);
DISPLAY 1.021277 (-3975 3250);
PAINT ORANGE (-3975 3250);
DISPLAY INVISIBLE (-3975 3250);
FORCEPROP 1 LAST PATH I109
J 0
(-3375 3100);
PAINT GREEN (-3375 3100);
DISPLAY INVISIBLE (-3375 3100);
FORCEADD GND_NIC..1
(-4175 1300);
FORCEPROP 3 LASTPIN (-4175 1350) SIG_NAME GND_NIC\g
J 0
(-4165 1360);
DISPLAY 0.659574 (-4165 1360);
PAINT MONO (-4165 1360);
DISPLAY INVISIBLE (-4165 1360);
FORCEPROP 1 LAST HDL_POWER GND_NIC
J 1
(-4150 1225);
DISPLAY 0.617021 (-4150 1225);
PAINT GREEN (-4150 1225);
FORCEPROP 1 LAST BODY_TYPE PLUMBING
J 0
(-4220 1257);
DISPLAY 0.340426 (-4220 1257);
PAINT GREEN (-4220 1257);
DISPLAY INVISIBLE (-4220 1257);
FORCEPROP 1 LAST VOLTAGE 0.0V
J 0
(-4220 1257);
DISPLAY 0.340426 (-4220 1257);
PAINT SKYBLUE (-4220 1257);
DISPLAY INVISIBLE (-4220 1257);
FORCEPROP 2 LAST CDS_LIB mstr_symbols
J 0
(-4175 1300);
PAINT ORANGE (-4175 1300);
DISPLAY INVISIBLE (-4175 1300);
FORCEPROP 1 LAST PATH I110
J 0
(-4100 1300);
DISPLAY 0.872340 (-4100 1300);
PAINT AQUA (-4100 1300);
DISPLAY INVISIBLE (-4100 1300);
FORCEADD GND..1
(-4700 1300);
FORCEPROP 3 LASTPIN (-4700 1350) SIG_NAME GND\g
J 0
(-4690 1360);
DISPLAY 0.659574 (-4690 1360);
PAINT MONO (-4690 1360);
DISPLAY INVISIBLE (-4690 1360);
FORCEPROP 1 LAST VOLTAGE 0.0V
J 0
(-4745 1257);
DISPLAY 0.340426 (-4745 1257);
PAINT SKYBLUE (-4745 1257);
DISPLAY INVISIBLE (-4745 1257);
FORCEPROP 1 LAST BODY_TYPE PLUMBING
J 0
(-4745 1257);
DISPLAY 0.340426 (-4745 1257);
PAINT GREEN (-4745 1257);
DISPLAY INVISIBLE (-4745 1257);
FORCEPROP 1 LAST SIZE 1B
J 0
(-4625 1250);
DISPLAY 0.872340 (-4625 1250);
PAINT AQUA (-4625 1250);
DISPLAY INVISIBLE (-4625 1250);
FORCEPROP 2 LAST CDS_LIB mstr_symbols
J 0
(-4700 1300);
PAINT ORANGE (-4700 1300);
DISPLAY INVISIBLE (-4700 1300);
FORCEPROP 1 LAST PATH I111
J 0
(-4625 1300);
DISPLAY 0.872340 (-4625 1300);
PAINT AQUA (-4625 1300);
DISPLAY INVISIBLE (-4625 1300);
FORCEPROP 1 LAST HDL_POWER GND
J 0
(-4700 1450);
DISPLAY 0.872340 (-4700 1450);
PAINT GREEN (-4700 1450);
DISPLAY INVISIBLE (-4700 1450);
FORCEADD RES..1
(-4450 1400);
FORCEPROP 1 LAST WATTAGE 1/16W
J 2
(-4475 1250);
DISPLAY 0.617021 (-4475 1250);
PAINT SKYBLUE (-4475 1250);
FORCEPROP 1 LAST PACK_TYPE 0402
J 0
(-4575 1200);
DISPLAY 0.617021 (-4575 1200);
PAINT SKYBLUE (-4575 1200);
FORCEPROP 1 LASTPIN (-4550 1400) $PN 1
J 0
(-4538 1412);
DISPLAY 0.617021 (-4538 1412);
PAINT ORANGE (-4538 1412);
FORCEPROP 1 LAST VALUE 0.0
J 2
(-4475 1300);
DISPLAY 0.617021 (-4475 1300);
PAINT SKYBLUE (-4475 1300);
FORCEPROP 1 LAST LOCATION R1U51
J 0
(-4500 1450);
DISPLAY 0.617021 (-4500 1450);
PAINT AQUA (-4500 1450);
FORCEPROP 1 LASTPIN (-4350 1400) $PN 2
J 0
(-4388 1412);
DISPLAY 0.617021 (-4388 1412);
PAINT ORANGE (-4388 1412);
FORCEPROP 1 LAST TOLERANCE 5%
J 0
(-4450 1300);
DISPLAY 0.617021 (-4450 1300);
PAINT SKYBLUE (-4450 1300);
FORCEPROP 1 LAST PART_NUMBER G21497-005
J 0
(-4500 1500);
DISPLAY 0.617021 (-4500 1500);
PAINT BLUE (-4500 1500);
FORCEPROP 1 LAST MATERIAL CHIP
J 0
(-4450 1250);
DISPLAY 0.617021 (-4450 1250);
PAINT SKYBLUE (-4450 1250);
FORCEPROP 2 LAST CDS_LOCATION R1U51
J 0
(-4500 1450);
DISPLAY 0.617021 (-4500 1450);
PAINT AQUA (-4500 1450);
DISPLAY INVISIBLE (-4500 1450);
FORCEPROP 2 LAST CDS_LIB mstr_discrete
J 0
(-4450 1400);
PAINT ORANGE (-4450 1400);
DISPLAY INVISIBLE (-4450 1400);
FORCEPROP 0 LAST ROOM NIC_SPRV
J 0
(-4500 1600);
DISPLAY 1.021277 (-4500 1600);
PAINT ORANGE (-4500 1600);
DISPLAY INVISIBLE (-4500 1600);
FORCEPROP 1 LAST PATH I112
J 0
(-4500 1550);
DISPLAY 0.978723 (-4500 1550);
PAINT WHITE (-4500 1550);
DISPLAY INVISIBLE (-4500 1550);
FORCEPROP 2 LAST SEC 1
J 0
(-4500 1600);
DISPLAY 0.680851 (-4500 1600);
PAINT MONO (-4500 1600);
DISPLAY INVISIBLE (-4500 1600);
FORCEPROP 0 LAST BOM_COST NT_GBE_BASE
J 0
(-4500 1700);
DISPLAY 1.021277 (-4500 1700);
PAINT ORANGE (-4500 1700);
DISPLAY INVISIBLE (-4500 1700);
FORCEPROP 2 LAST SEC_TYPE 0402
J 0
(-4500 1600);
DISPLAY 1.021277 (-4500 1600);
PAINT ORANGE (-4500 1600);
DISPLAY INVISIBLE (-4500 1600);
FORCEADD GND_NIC..1
(-4175 925);
FORCEPROP 3 LASTPIN (-4175 975) SIG_NAME GND_NIC\g
J 0
(-4165 985);
DISPLAY 0.659574 (-4165 985);
PAINT MONO (-4165 985);
DISPLAY INVISIBLE (-4165 985);
FORCEPROP 1 LAST HDL_POWER GND_NIC
J 1
(-4150 850);
DISPLAY 0.617021 (-4150 850);
PAINT GREEN (-4150 850);
FORCEPROP 1 LAST VOLTAGE 0.0V
J 0
(-4220 882);
DISPLAY 0.340426 (-4220 882);
PAINT SKYBLUE (-4220 882);
DISPLAY INVISIBLE (-4220 882);
FORCEPROP 2 LAST CDS_LIB mstr_symbols
J 0
(-4175 925);
PAINT ORANGE (-4175 925);
DISPLAY INVISIBLE (-4175 925);
FORCEPROP 1 LAST BODY_TYPE PLUMBING
J 0
(-4220 882);
DISPLAY 0.340426 (-4220 882);
PAINT GREEN (-4220 882);
DISPLAY INVISIBLE (-4220 882);
FORCEPROP 1 LAST PATH I113
J 0
(-4100 925);
DISPLAY 0.872340 (-4100 925);
PAINT AQUA (-4100 925);
DISPLAY INVISIBLE (-4100 925);
FORCEADD RES..1
(-4450 1000);
FORCEPROP 1 LAST WATTAGE 1/16W
J 2
(-4475 850);
DISPLAY 0.617021 (-4475 850);
PAINT SKYBLUE (-4475 850);
FORCEPROP 1 LAST VALUE 0.0
J 2
(-4475 900);
DISPLAY 0.617021 (-4475 900);
PAINT SKYBLUE (-4475 900);
FORCEPROP 1 LAST TOLERANCE 5%
J 0
(-4450 900);
DISPLAY 0.617021 (-4450 900);
PAINT SKYBLUE (-4450 900);
FORCEPROP 1 LAST PACK_TYPE 0402
J 0
(-4575 800);
DISPLAY 0.617021 (-4575 800);
PAINT SKYBLUE (-4575 800);
FORCEPROP 1 LAST MATERIAL CHIP
J 0
(-4450 850);
DISPLAY 0.617021 (-4450 850);
PAINT SKYBLUE (-4450 850);
FORCEPROP 1 LASTPIN (-4350 1000) $PN 2
J 0
(-4388 1012);
DISPLAY 0.617021 (-4388 1012);
PAINT ORANGE (-4388 1012);
FORCEPROP 1 LASTPIN (-4550 1000) $PN 1
J 0
(-4538 1012);
DISPLAY 0.617021 (-4538 1012);
PAINT ORANGE (-4538 1012);
FORCEPROP 1 LAST LOCATION R1U3
J 0
(-4500 1050);
DISPLAY 0.617021 (-4500 1050);
PAINT AQUA (-4500 1050);
FORCEPROP 1 LAST PART_NUMBER G21497-005
J 0
(-4500 1100);
DISPLAY 0.617021 (-4500 1100);
PAINT BLUE (-4500 1100);
FORCEPROP 2 LAST CDS_LIB mstr_discrete
J 0
(-4450 1000);
PAINT ORANGE (-4450 1000);
DISPLAY INVISIBLE (-4450 1000);
FORCEPROP 0 LAST ROOM NIC_SPRV
J 0
(-4500 1200);
DISPLAY 1.021277 (-4500 1200);
PAINT ORANGE (-4500 1200);
DISPLAY INVISIBLE (-4500 1200);
FORCEPROP 1 LAST PATH I114
J 0
(-4500 1150);
DISPLAY 0.978723 (-4500 1150);
PAINT WHITE (-4500 1150);
DISPLAY INVISIBLE (-4500 1150);
FORCEPROP 2 LAST CDS_LOCATION R1U3
J 0
(-4500 1050);
DISPLAY 0.617021 (-4500 1050);
PAINT AQUA (-4500 1050);
DISPLAY INVISIBLE (-4500 1050);
FORCEPROP 2 LAST SEC 1
J 0
(-4500 1200);
DISPLAY 0.680851 (-4500 1200);
PAINT MONO (-4500 1200);
DISPLAY INVISIBLE (-4500 1200);
FORCEPROP 2 LAST SEC_TYPE 0402
J 0
(-4500 1200);
DISPLAY 1.021277 (-4500 1200);
PAINT ORANGE (-4500 1200);
DISPLAY INVISIBLE (-4500 1200);
FORCEPROP 0 LAST BOM_COST NT_GBE_BASE
J 0
(-4500 1300);
DISPLAY 1.021277 (-4500 1300);
PAINT ORANGE (-4500 1300);
DISPLAY INVISIBLE (-4500 1300);
FORCEADD GND..1
(-4700 900);
FORCEPROP 3 LASTPIN (-4700 950) SIG_NAME GND\g
J 0
(-4690 960);
DISPLAY 0.659574 (-4690 960);
PAINT MONO (-4690 960);
DISPLAY INVISIBLE (-4690 960);
FORCEPROP 1 LAST PATH I115
J 0
(-4625 900);
DISPLAY 0.872340 (-4625 900);
PAINT AQUA (-4625 900);
DISPLAY INVISIBLE (-4625 900);
FORCEPROP 2 LAST CDS_LIB mstr_symbols
J 0
(-4700 900);
PAINT ORANGE (-4700 900);
DISPLAY INVISIBLE (-4700 900);
FORCEPROP 1 LAST SIZE 1B
J 0
(-4625 850);
DISPLAY 0.872340 (-4625 850);
PAINT AQUA (-4625 850);
DISPLAY INVISIBLE (-4625 850);
FORCEPROP 1 LAST BODY_TYPE PLUMBING
J 0
(-4745 857);
DISPLAY 0.340426 (-4745 857);
PAINT GREEN (-4745 857);
DISPLAY INVISIBLE (-4745 857);
FORCEPROP 1 LAST VOLTAGE 0.0V
J 0
(-4745 857);
DISPLAY 0.340426 (-4745 857);
PAINT SKYBLUE (-4745 857);
DISPLAY INVISIBLE (-4745 857);
FORCEPROP 1 LAST HDL_POWER GND
J 0
(-4700 1050);
DISPLAY 0.872340 (-4700 1050);
PAINT GREEN (-4700 1050);
DISPLAY INVISIBLE (-4700 1050);
FORCEADD OFFPAGE..6
(-5000 2850);
FORCEPROP 2 LAST $XR0 141 
J 0
(-5280 2850);
DISPLAY 0.638298 (-5280 2850);
PAINT MONO (-5280 2850);
FORCEPROP 1 LAST COMMENT_BODY TRUE
J 0
(-4900 2775);
DISPLAY 0.872340 (-4900 2775);
PAINT GREEN (-4900 2775);
DISPLAY INVISIBLE (-4900 2775);
FORCEPROP 2 LAST CDS_LIB mstr_standard
J 0
(-5000 2850);
PAINT ORANGE (-5000 2850);
DISPLAY INVISIBLE (-5000 2850);
FORCEPROP 2 LAST PATH I18
J 0
(-4950 2925);
DISPLAY 1.021277 (-4950 2925);
PAINT ORANGE (-4950 2925);
DISPLAY INVISIBLE (-4950 2925);
FORCEPROP 1 LAST OFFPAGE TRUE
J 0
(-4675 2725);
DISPLAY 0.872340 (-4675 2725);
PAINT GREEN (-4675 2725);
DISPLAY INVISIBLE (-4675 2725);
FORCEADD OFFPAGE..6
(-5000 2750);
FORCEPROP 2 LAST $XR0 141 
J 0
(-5280 2750);
DISPLAY 0.638298 (-5280 2750);
PAINT MONO (-5280 2750);
FORCEPROP 2 LAST CDS_LIB mstr_standard
J 0
(-5000 2750);
PAINT ORANGE (-5000 2750);
DISPLAY INVISIBLE (-5000 2750);
FORCEPROP 1 LAST COMMENT_BODY TRUE
J 0
(-4900 2675);
DISPLAY 0.872340 (-4900 2675);
PAINT GREEN (-4900 2675);
DISPLAY INVISIBLE (-4900 2675);
FORCEPROP 2 LAST PATH I19
J 0
(-4950 2825);
DISPLAY 1.021277 (-4950 2825);
PAINT ORANGE (-4950 2825);
DISPLAY INVISIBLE (-4950 2825);
FORCEPROP 1 LAST OFFPAGE TRUE
J 0
(-4675 2625);
DISPLAY 0.872340 (-4675 2625);
PAINT GREEN (-4675 2625);
DISPLAY INVISIBLE (-4675 2625);
FORCEADD OFFPAGE..6
(-5000 2650);
FORCEPROP 2 LAST $XR0 141 
J 0
(-5280 2650);
DISPLAY 0.638298 (-5280 2650);
PAINT MONO (-5280 2650);
FORCEPROP 1 LAST OFFPAGE TRUE
J 0
(-4675 2525);
DISPLAY 0.872340 (-4675 2525);
PAINT GREEN (-4675 2525);
DISPLAY INVISIBLE (-4675 2525);
FORCEPROP 2 LAST CDS_LIB mstr_standard
J 0
(-5000 2650);
PAINT ORANGE (-5000 2650);
DISPLAY INVISIBLE (-5000 2650);
FORCEPROP 1 LAST COMMENT_BODY TRUE
J 0
(-4900 2575);
DISPLAY 0.872340 (-4900 2575);
PAINT GREEN (-4900 2575);
DISPLAY INVISIBLE (-4900 2575);
FORCEPROP 2 LAST PATH I20
J 0
(-4950 2725);
DISPLAY 1.021277 (-4950 2725);
PAINT ORANGE (-4950 2725);
DISPLAY INVISIBLE (-4950 2725);
FORCEADD OFFPAGE..6
(-5000 2550);
FORCEPROP 2 LAST $XR0 141 
J 0
(-5280 2550);
DISPLAY 0.638298 (-5280 2550);
PAINT MONO (-5280 2550);
FORCEPROP 1 LAST COMMENT_BODY TRUE
J 0
(-4900 2475);
DISPLAY 0.872340 (-4900 2475);
PAINT GREEN (-4900 2475);
DISPLAY INVISIBLE (-4900 2475);
FORCEPROP 1 LAST OFFPAGE TRUE
J 0
(-4675 2425);
DISPLAY 0.872340 (-4675 2425);
PAINT GREEN (-4675 2425);
DISPLAY INVISIBLE (-4675 2425);
FORCEPROP 2 LAST CDS_LIB mstr_standard
J 0
(-5000 2550);
PAINT ORANGE (-5000 2550);
DISPLAY INVISIBLE (-5000 2550);
FORCEPROP 2 LAST PATH I21
J 0
(-4950 2625);
DISPLAY 1.021277 (-4950 2625);
PAINT ORANGE (-4950 2625);
DISPLAY INVISIBLE (-4950 2625);
FORCEADD OFFPAGE..3
(-2150 2850);
FORCEPROP 2 LAST $XR0 141 
J 0
(-1936 2850);
DISPLAY 0.638298 (-1936 2850);
PAINT MONO (-1936 2850);
FORCEPROP 1 LAST COMMENT_BODY TRUE
J 0
(-2200 2750);
DISPLAY 0.872340 (-2200 2750);
PAINT GREEN (-2200 2750);
DISPLAY INVISIBLE (-2200 2750);
FORCEPROP 2 LAST CDS_LIB mstr_standard
J 0
(-2150 2850);
PAINT ORANGE (-2150 2850);
DISPLAY INVISIBLE (-2150 2850);
FORCEPROP 2 LAST PATH I22
J 0
(-2100 2925);
DISPLAY 1.021277 (-2100 2925);
PAINT ORANGE (-2100 2925);
DISPLAY INVISIBLE (-2100 2925);
FORCEPROP 1 LAST OFFPAGE TRUE
J 0
(-1825 2725);
DISPLAY 0.872340 (-1825 2725);
PAINT GREEN (-1825 2725);
DISPLAY INVISIBLE (-1825 2725);
FORCEADD OFFPAGE..3
(-2150 2750);
FORCEPROP 2 LAST $XR0 141 
J 0
(-1936 2750);
DISPLAY 0.638298 (-1936 2750);
PAINT MONO (-1936 2750);
FORCEPROP 1 LAST COMMENT_BODY TRUE
J 0
(-2200 2650);
DISPLAY 0.872340 (-2200 2650);
PAINT GREEN (-2200 2650);
DISPLAY INVISIBLE (-2200 2650);
FORCEPROP 2 LAST CDS_LIB mstr_standard
J 0
(-2150 2750);
PAINT ORANGE (-2150 2750);
DISPLAY INVISIBLE (-2150 2750);
FORCEPROP 1 LAST OFFPAGE TRUE
J 0
(-1825 2625);
DISPLAY 0.872340 (-1825 2625);
PAINT GREEN (-1825 2625);
DISPLAY INVISIBLE (-1825 2625);
FORCEPROP 2 LAST PATH I23
J 0
(-1950 2825);
DISPLAY 1.021277 (-1950 2825);
PAINT ORANGE (-1950 2825);
DISPLAY INVISIBLE (-1950 2825);
FORCEADD OFFPAGE..3
(-2150 2650);
FORCEPROP 2 LAST $XR0 141 
J 0
(-1936 2650);
DISPLAY 0.638298 (-1936 2650);
PAINT MONO (-1936 2650);
FORCEPROP 1 LAST COMMENT_BODY TRUE
J 0
(-2200 2550);
DISPLAY 0.872340 (-2200 2550);
PAINT GREEN (-2200 2550);
DISPLAY INVISIBLE (-2200 2550);
FORCEPROP 2 LAST CDS_LIB mstr_standard
J 0
(-2150 2650);
PAINT ORANGE (-2150 2650);
DISPLAY INVISIBLE (-2150 2650);
FORCEPROP 1 LAST OFFPAGE TRUE
J 0
(-1825 2525);
DISPLAY 0.872340 (-1825 2525);
PAINT GREEN (-1825 2525);
DISPLAY INVISIBLE (-1825 2525);
FORCEPROP 2 LAST PATH I24
J 0
(-1950 2725);
DISPLAY 1.021277 (-1950 2725);
PAINT ORANGE (-1950 2725);
DISPLAY INVISIBLE (-1950 2725);
FORCEADD OFFPAGE..3
(-2150 2550);
FORCEPROP 2 LAST $XR0 141 
J 0
(-1936 2550);
DISPLAY 0.638298 (-1936 2550);
PAINT MONO (-1936 2550);
FORCEPROP 1 LAST COMMENT_BODY TRUE
J 0
(-2200 2450);
DISPLAY 0.872340 (-2200 2450);
PAINT GREEN (-2200 2450);
DISPLAY INVISIBLE (-2200 2450);
FORCEPROP 2 LAST CDS_LIB mstr_standard
J 0
(-2150 2550);
PAINT ORANGE (-2150 2550);
DISPLAY INVISIBLE (-2150 2550);
FORCEPROP 1 LAST OFFPAGE TRUE
J 0
(-1825 2425);
DISPLAY 0.872340 (-1825 2425);
PAINT GREEN (-1825 2425);
DISPLAY INVISIBLE (-1825 2425);
FORCEPROP 2 LAST PATH I25
J 0
(-1950 2625);
DISPLAY 1.021277 (-1950 2625);
PAINT ORANGE (-1950 2625);
DISPLAY INVISIBLE (-1950 2625);
FORCEADD RES..1
(-2375 2400);
FORCEPROP 1 LAST MATERIAL CHIP
J 0
(-2650 2400);
DISPLAY 0.617021 (-2650 2400);
PAINT SKYBLUE (-2650 2400);
FORCEPROP 1 LASTPIN (-2475 2400) $PN 1
J 0
(-2463 2412);
DISPLAY 0.617021 (-2463 2412);
PAINT ORANGE (-2463 2412);
FORCEPROP 1 LAST LOCATION R9G3
J 0
(-2425 2450);
DISPLAY 0.617021 (-2425 2450);
PAINT AQUA (-2425 2450);
FORCEPROP 1 LASTPIN (-2275 2400) $PN 2
J 0
(-2313 2412);
DISPLAY 0.617021 (-2313 2412);
PAINT ORANGE (-2313 2412);
FORCEPROP 1 LAST TOLERANCE 1%
J 0
(-2200 2400);
DISPLAY 0.617021 (-2200 2400);
PAINT SKYBLUE (-2200 2400);
FORCEPROP 1 LAST WATTAGE 1/16W
J 2
(-2050 2350);
DISPLAY 0.617021 (-2050 2350);
PAINT SKYBLUE (-2050 2350);
FORCEPROP 1 LAST PACK_TYPE 0402
J 0
(-2300 2350);
DISPLAY 0.617021 (-2300 2350);
PAINT SKYBLUE (-2300 2350);
FORCEPROP 1 LAST PART_NUMBER G21796-009
J 0
(-2250 2450);
DISPLAY 0.617021 (-2250 2450);
PAINT BLUE (-2250 2450);
FORCEPROP 1 LAST VALUE 150.0
J 2
(-1975 2400);
DISPLAY 0.617021 (-1975 2400);
PAINT SKYBLUE (-1975 2400);
FORCEPROP 2 LAST CDS_LOCATION R9G3
J 0
(-2425 2450);
DISPLAY 0.617021 (-2425 2450);
PAINT AQUA (-2425 2450);
DISPLAY INVISIBLE (-2425 2450);
FORCEPROP 2 LAST CDS_LIB mstr_discrete
J 0
(-2375 2400);
PAINT ORANGE (-2375 2400);
DISPLAY INVISIBLE (-2375 2400);
FORCEPROP 2 LAST ROOM NIC_SPRV
J 0
(-2250 2500);
DISPLAY 1.021277 (-2250 2500);
PAINT ORANGE (-2250 2500);
DISPLAY INVISIBLE (-2250 2500);
FORCEPROP 1 LAST PATH I28
J 0
(-2425 2550);
DISPLAY 0.978723 (-2425 2550);
PAINT WHITE (-2425 2550);
DISPLAY INVISIBLE (-2425 2550);
FORCEPROP 2 LAST BOM_COST NT_GBE_BASE
J 0
(-2250 2550);
DISPLAY 1.021277 (-2250 2550);
PAINT ORANGE (-2250 2550);
DISPLAY INVISIBLE (-2250 2550);
FORCEPROP 2 LAST SEC 1
J 0
(-2425 2600);
DISPLAY 0.680851 (-2425 2600);
PAINT MONO (-2425 2600);
DISPLAY INVISIBLE (-2425 2600);
FORCEPROP 2 LAST SEC_TYPE 0402
J 0
(-2425 2600);
DISPLAY 1.021277 (-2425 2600);
PAINT ORANGE (-2425 2600);
DISPLAY INVISIBLE (-2425 2600);
FORCEADD OFFPAGE..4
(-1475 2400);
FORCEPROP 2 LAST $XR0 139 
J 0
(-1289 2400);
DISPLAY 0.638298 (-1289 2400);
PAINT MONO (-1289 2400);
FORCEPROP 1 LAST COMMENT_BODY TRUE
J 0
(-1500 2300);
DISPLAY 0.872340 (-1500 2300);
PAINT GREEN (-1500 2300);
DISPLAY INVISIBLE (-1500 2300);
FORCEPROP 2 LAST CDS_LIB mstr_standard
J 0
(-1475 2400);
PAINT ORANGE (-1475 2400);
DISPLAY INVISIBLE (-1475 2400);
FORCEPROP 2 LAST PATH I29
J 0
(-1425 2475);
DISPLAY 1.021277 (-1425 2475);
PAINT ORANGE (-1425 2475);
DISPLAY INVISIBLE (-1425 2475);
FORCEPROP 1 LAST OFFPAGE TRUE
J 0
(-1150 2275);
DISPLAY 0.872340 (-1150 2275);
PAINT GREEN (-1150 2275);
DISPLAY INVISIBLE (-1150 2275);
FORCEADD RES..1
(-2550 2300);
FORCEPROP 1 LASTPIN (-2650 2300) $PN 1
J 0
(-2638 2312);
DISPLAY 0.617021 (-2638 2312);
PAINT ORANGE (-2638 2312);
FORCEPROP 1 LAST WATTAGE 1/16W
J 2
(-2575 2250);
DISPLAY 0.617021 (-2575 2250);
PAINT SKYBLUE (-2575 2250);
FORCEPROP 1 LAST PART_NUMBER G21796-009
J 0
(-2700 2200);
DISPLAY 0.617021 (-2700 2200);
PAINT BLUE (-2700 2200);
FORCEPROP 1 LAST LOCATION R9G2
J 0
(-2600 2350);
DISPLAY 0.617021 (-2600 2350);
PAINT AQUA (-2600 2350);
FORCEPROP 1 LAST PACK_TYPE 0402
J 0
(-2475 2250);
DISPLAY 0.617021 (-2475 2250);
PAINT SKYBLUE (-2475 2250);
FORCEPROP 1 LAST TOLERANCE 1%
J 0
(-2375 2300);
DISPLAY 0.617021 (-2375 2300);
PAINT SKYBLUE (-2375 2300);
FORCEPROP 1 LASTPIN (-2450 2300) $PN 2
J 0
(-2488 2312);
DISPLAY 0.617021 (-2488 2312);
PAINT ORANGE (-2488 2312);
FORCEPROP 1 LAST VALUE 150.0
J 2
(-2175 2300);
DISPLAY 0.617021 (-2175 2300);
PAINT SKYBLUE (-2175 2300);
FORCEPROP 1 LAST MATERIAL CHIP
J 0
(-2375 2250);
DISPLAY 0.617021 (-2375 2250);
PAINT SKYBLUE (-2375 2250);
FORCEPROP 2 LAST ROOM NIC_SPRV
J 0
(-2600 2400);
DISPLAY 1.021277 (-2600 2400);
PAINT ORANGE (-2600 2400);
DISPLAY INVISIBLE (-2600 2400);
FORCEPROP 1 LAST PATH I30
J 0
(-2600 2450);
DISPLAY 0.978723 (-2600 2450);
PAINT WHITE (-2600 2450);
DISPLAY INVISIBLE (-2600 2450);
FORCEPROP 2 LAST CDS_LOCATION R9G2
J 0
(-2600 2350);
DISPLAY 0.617021 (-2600 2350);
PAINT AQUA (-2600 2350);
DISPLAY INVISIBLE (-2600 2350);
FORCEPROP 2 LAST SEC 1
J 0
(-2600 2500);
DISPLAY 0.680851 (-2600 2500);
PAINT MONO (-2600 2500);
DISPLAY INVISIBLE (-2600 2500);
FORCEPROP 2 LAST SEC_TYPE 0402
J 0
(-2600 2500);
DISPLAY 1.021277 (-2600 2500);
PAINT ORANGE (-2600 2500);
DISPLAY INVISIBLE (-2600 2500);
FORCEPROP 2 LAST BOM_COST NT_GBE_BASE
J 0
(-2600 2450);
DISPLAY 1.021277 (-2600 2450);
PAINT ORANGE (-2600 2450);
DISPLAY INVISIBLE (-2600 2450);
FORCEPROP 2 LAST CDS_LIB mstr_discrete
J 0
(-2550 2300);
PAINT ORANGE (-2550 2300);
DISPLAY INVISIBLE (-2550 2300);
FORCEADD OFFPAGE..4
(-1475 2300);
FORCEPROP 2 LAST $XR0 139 
J 0
(-1289 2300);
DISPLAY 0.638298 (-1289 2300);
PAINT MONO (-1289 2300);
FORCEPROP 1 LAST COMMENT_BODY TRUE
J 0
(-1500 2200);
DISPLAY 0.872340 (-1500 2200);
PAINT GREEN (-1500 2200);
DISPLAY INVISIBLE (-1500 2200);
FORCEPROP 2 LAST CDS_LIB mstr_standard
J 0
(-1475 2300);
PAINT ORANGE (-1475 2300);
DISPLAY INVISIBLE (-1475 2300);
FORCEPROP 2 LAST PATH I31
J 0
(-1300 2375);
DISPLAY 1.021277 (-1300 2375);
PAINT ORANGE (-1300 2375);
DISPLAY INVISIBLE (-1300 2375);
FORCEPROP 1 LAST OFFPAGE TRUE
J 0
(-1150 2175);
DISPLAY 0.872340 (-1150 2175);
PAINT GREEN (-1150 2175);
DISPLAY INVISIBLE (-1150 2175);
FORCEADD CAP_A..1
(-5575 2150);
FORCEPROP 1 LAST PACK_TYPE 0402V
J 0
(-5525 1950);
DISPLAY 0.617021 (-5525 1950);
PAINT SKYBLUE (-5525 1950);
FORCEPROP 1 LAST PART_NUMBER A36096-030
J 0
(-5525 2000);
DISPLAY 0.617021 (-5525 2000);
PAINT BLUE (-5525 2000);
FORCEPROP 1 LASTPIN (-5575 2050) $PN 2
J 0
(-5565 2030);
DISPLAY 0.617021 (-5565 2030);
PAINT ORANGE (-5565 2030);
FORCEPROP 1 LASTPIN (-5575 2250) $PN 1
J 0
(-5565 2230);
DISPLAY 0.617021 (-5565 2230);
PAINT ORANGE (-5565 2230);
FORCEPROP 1 LAST LOCATION C9G7
J 0
(-5525 2250);
DISPLAY 0.617021 (-5525 2250);
PAINT AQUA (-5525 2250);
FORCEPROP 1 LAST TOLERANCE 10%
J 0
(-5525 2100);
DISPLAY 0.617021 (-5525 2100);
PAINT SKYBLUE (-5525 2100);
FORCEPROP 1 LAST VOLTAGE 16V
J 0
(-5525 2150);
DISPLAY 0.617021 (-5525 2150);
PAINT SKYBLUE (-5525 2150);
FORCEPROP 1 LAST MATERIAL X7R
J 0
(-5525 2050);
DISPLAY 0.617021 (-5525 2050);
PAINT SKYBLUE (-5525 2050);
FORCEPROP 1 LAST VALUE 0.1UF
J 0
(-5525 2200);
DISPLAY 0.617021 (-5525 2200);
PAINT SKYBLUE (-5525 2200);
FORCEPROP 2 LAST CDS_LIB dev_discrete
J 0
(-5575 2150);
PAINT ORANGE (-5575 2150);
DISPLAY INVISIBLE (-5575 2150);
FORCEPROP 2 LAST CDS_LOCATION C9G7
J 0
(-5525 2250);
DISPLAY 0.617021 (-5525 2250);
PAINT AQUA (-5525 2250);
DISPLAY INVISIBLE (-5525 2250);
FORCEPROP 2 LAST ROOM NIC_SPRV
J 0
(-5525 2300);
DISPLAY 1.021277 (-5525 2300);
PAINT ORANGE (-5525 2300);
DISPLAY INVISIBLE (-5525 2300);
FORCEPROP 1 LAST PATH I33
J 0
(-5525 2300);
DISPLAY 0.978723 (-5525 2300);
PAINT WHITE (-5525 2300);
DISPLAY INVISIBLE (-5525 2300);
FORCEPROP 2 LAST CDS_SEC 1
J 0
(-5525 2300);
PAINT ORANGE (-5525 2300);
DISPLAY INVISIBLE (-5525 2300);
FORCEPROP 2 LAST BOM_COST NT_GBE_BASE
J 0
(-5525 2350);
DISPLAY 1.021277 (-5525 2350);
PAINT ORANGE (-5525 2350);
DISPLAY INVISIBLE (-5525 2350);
FORCEPROP 2 LAST SEC_TYPE 0402V
J 0
(-5525 2350);
DISPLAY 1.021277 (-5525 2350);
PAINT ORANGE (-5525 2350);
DISPLAY INVISIBLE (-5525 2350);
FORCEPROP 2 LAST SEC 1
J 0
(-5525 2350);
PAINT MONO (-5525 2350);
DISPLAY INVISIBLE (-5525 2350);
FORCEADD GND..1
(-5575 1700);
FORCEPROP 3 LASTPIN (-5575 1750) SIG_NAME GND\g
J 0
(-5565 1760);
DISPLAY 0.659574 (-5565 1760);
PAINT MONO (-5565 1760);
DISPLAY INVISIBLE (-5565 1760);
FORCEPROP 1 LAST HDL_POWER GND
J 0
(-5575 1850);
DISPLAY 0.872340 (-5575 1850);
PAINT GREEN (-5575 1850);
DISPLAY INVISIBLE (-5575 1850);
FORCEPROP 1 LAST PATH I35
J 0
(-5500 1700);
DISPLAY 0.872340 (-5500 1700);
PAINT AQUA (-5500 1700);
DISPLAY INVISIBLE (-5500 1700);
FORCEPROP 1 LAST BODY_TYPE PLUMBING
J 0
(-5620 1657);
DISPLAY 0.340426 (-5620 1657);
PAINT GREEN (-5620 1657);
DISPLAY INVISIBLE (-5620 1657);
FORCEPROP 2 LAST CDS_LIB mstr_symbols
J 0
(-5575 1700);
PAINT ORANGE (-5575 1700);
DISPLAY INVISIBLE (-5575 1700);
FORCEPROP 1 LAST SIZE 1B
J 0
(-5500 1650);
DISPLAY 0.872340 (-5500 1650);
PAINT AQUA (-5500 1650);
DISPLAY INVISIBLE (-5500 1650);
FORCEPROP 1 LAST VOLTAGE 0.0V
J 0
(-5620 1657);
DISPLAY 0.340426 (-5620 1657);
PAINT SKYBLUE (-5620 1657);
DISPLAY INVISIBLE (-5620 1657);
FORCEADD CAP..1
(-1700 925);
FORCEPROP 1 LAST TOLERANCE 10%
J 0
(-1650 875);
DISPLAY 0.617021 (-1650 875);
PAINT SKYBLUE (-1650 875);
FORCEPROP 1 LAST VOLTAGE 50V
J 0
(-1650 925);
DISPLAY 0.617021 (-1650 925);
PAINT SKYBLUE (-1650 925);
FORCEPROP 1 LAST MATERIAL X7R
J 0
(-1650 825);
DISPLAY 0.617021 (-1650 825);
PAINT SKYBLUE (-1650 825);
FORCEPROP 1 LASTPIN (-1700 825) $PN 2
J 0
(-1690 805);
DISPLAY 0.617021 (-1690 805);
PAINT ORANGE (-1690 805);
FORCEPROP 1 LAST PART_NUMBER A36096-049
J 0
(-1650 775);
DISPLAY 0.617021 (-1650 775);
PAINT BLUE (-1650 775);
FORCEPROP 1 LAST VALUE 470PF
J 0
(-1650 975);
DISPLAY 0.617021 (-1650 975);
PAINT SKYBLUE (-1650 975);
FORCEPROP 1 LAST PACK_TYPE 0402LF
J 0
(-1650 725);
DISPLAY 0.617021 (-1650 725);
PAINT SKYBLUE (-1650 725);
FORCEPROP 1 LAST LOCATION C9G2
J 0
(-1525 900);
DISPLAY 0.617021 (-1525 900);
PAINT AQUA (-1525 900);
FORCEPROP 1 LASTPIN (-1700 1025) $PN 1
J 0
(-1690 1005);
DISPLAY 0.617021 (-1690 1005);
PAINT ORANGE (-1690 1005);
FORCEPROP 2 LAST CDS_LIB mstr_discrete
J 0
(-1700 925);
PAINT ORANGE (-1700 925);
DISPLAY INVISIBLE (-1700 925);
FORCEPROP 2 LAST CDS_LOCATION C9G2
J 0
(-1525 900);
DISPLAY 0.617021 (-1525 900);
PAINT AQUA (-1525 900);
DISPLAY INVISIBLE (-1525 900);
FORCEPROP 2 LAST SEC 1
J 0
(-1650 1125);
PAINT MONO (-1650 1125);
DISPLAY INVISIBLE (-1650 1125);
FORCEPROP 2 LAST BOM_COST NT_GBE_BASE
J 0
(-1650 1075);
DISPLAY 1.021277 (-1650 1075);
PAINT ORANGE (-1650 1075);
DISPLAY INVISIBLE (-1650 1075);
FORCEPROP 2 LAST SEC_TYPE 0402LF
J 0
(-1650 1125);
DISPLAY 1.021277 (-1650 1125);
PAINT ORANGE (-1650 1125);
DISPLAY INVISIBLE (-1650 1125);
FORCEPROP 1 LAST PATH I36
J 0
(-1650 1075);
DISPLAY 0.978723 (-1650 1075);
PAINT WHITE (-1650 1075);
DISPLAY INVISIBLE (-1650 1075);
FORCEPROP 2 LAST ROOM NIC_SPRV
J 0
(-1650 1025);
DISPLAY 1.021277 (-1650 1025);
PAINT ORANGE (-1650 1025);
DISPLAY INVISIBLE (-1650 1025);
FORCEADD GND..1
(-1700 700);
FORCEPROP 3 LASTPIN (-1700 750) SIG_NAME GND\g
J 0
(-1690 760);
DISPLAY 0.659574 (-1690 760);
PAINT MONO (-1690 760);
DISPLAY INVISIBLE (-1690 760);
FORCEPROP 1 LAST VOLTAGE 0.0V
J 0
(-1745 657);
DISPLAY 0.340426 (-1745 657);
PAINT SKYBLUE (-1745 657);
DISPLAY INVISIBLE (-1745 657);
FORCEPROP 1 LAST SIZE 1B
J 0
(-1625 650);
DISPLAY 0.872340 (-1625 650);
PAINT AQUA (-1625 650);
DISPLAY INVISIBLE (-1625 650);
FORCEPROP 2 LAST CDS_LIB mstr_symbols
J 0
(-1700 700);
PAINT ORANGE (-1700 700);
DISPLAY INVISIBLE (-1700 700);
FORCEPROP 1 LAST BODY_TYPE PLUMBING
J 0
(-1745 657);
DISPLAY 0.340426 (-1745 657);
PAINT GREEN (-1745 657);
DISPLAY INVISIBLE (-1745 657);
FORCEPROP 1 LAST PATH I38
J 0
(-1625 700);
DISPLAY 0.872340 (-1625 700);
PAINT AQUA (-1625 700);
DISPLAY INVISIBLE (-1625 700);
FORCEPROP 1 LAST HDL_POWER GND
J 0
(-1700 850);
DISPLAY 0.872340 (-1700 850);
PAINT GREEN (-1700 850);
DISPLAY INVISIBLE (-1700 850);
FORCEADD OFFPAGE..1
(-5000 2800);
FORCEPROP 2 LAST $XR0 141 
J 0
(-5282 2800);
DISPLAY 0.638298 (-5282 2800);
PAINT MONO (-5282 2800);
FORCEPROP 1 LAST COMMENT_BODY TRUE
J 0
(-4875 2700);
DISPLAY 0.872340 (-4875 2700);
PAINT GREEN (-4875 2700);
DISPLAY INVISIBLE (-4875 2700);
FORCEPROP 2 LAST CDS_LIB mstr_standard
J 0
(-5000 2800);
PAINT ORANGE (-5000 2800);
DISPLAY INVISIBLE (-5000 2800);
FORCEPROP 2 LAST PATH I42
J 0
(-4950 2875);
DISPLAY 1.021277 (-4950 2875);
PAINT ORANGE (-4950 2875);
DISPLAY INVISIBLE (-4950 2875);
FORCEPROP 1 LAST OFFPAGE TRUE
J 0
(-4675 2675);
DISPLAY 0.872340 (-4675 2675);
PAINT GREEN (-4675 2675);
DISPLAY INVISIBLE (-4675 2675);
FORCEADD OFFPAGE..1
(-5000 2600);
FORCEPROP 2 LAST $XR0 141 
J 0
(-5282 2600);
DISPLAY 0.638298 (-5282 2600);
PAINT MONO (-5282 2600);
FORCEPROP 1 LAST COMMENT_BODY TRUE
J 0
(-4875 2500);
DISPLAY 0.872340 (-4875 2500);
PAINT GREEN (-4875 2500);
DISPLAY INVISIBLE (-4875 2500);
FORCEPROP 1 LAST OFFPAGE TRUE
J 0
(-4675 2475);
DISPLAY 0.872340 (-4675 2475);
PAINT GREEN (-4675 2475);
DISPLAY INVISIBLE (-4675 2475);
FORCEPROP 2 LAST CDS_LIB mstr_standard
J 0
(-5000 2600);
PAINT ORANGE (-5000 2600);
DISPLAY INVISIBLE (-5000 2600);
FORCEPROP 2 LAST PATH I43
J 0
(-4950 2675);
DISPLAY 1.021277 (-4950 2675);
PAINT ORANGE (-4950 2675);
DISPLAY INVISIBLE (-4950 2675);
FORCEADD OFFPAGE..4
(-2150 2800);
FORCEPROP 2 LAST $XR0 141 
J 0
(-1964 2800);
DISPLAY 0.638298 (-1964 2800);
PAINT MONO (-1964 2800);
FORCEPROP 1 LAST COMMENT_BODY TRUE
J 0
(-2175 2700);
DISPLAY 0.872340 (-2175 2700);
PAINT GREEN (-2175 2700);
DISPLAY INVISIBLE (-2175 2700);
FORCEPROP 2 LAST CDS_LIB mstr_standard
J 0
(-2150 2800);
PAINT ORANGE (-2150 2800);
DISPLAY INVISIBLE (-2150 2800);
FORCEPROP 1 LAST OFFPAGE TRUE
J 0
(-1825 2675);
DISPLAY 0.872340 (-1825 2675);
PAINT GREEN (-1825 2675);
DISPLAY INVISIBLE (-1825 2675);
FORCEPROP 2 LAST PATH I44
J 0
(-1950 2875);
DISPLAY 1.021277 (-1950 2875);
PAINT ORANGE (-1950 2875);
DISPLAY INVISIBLE (-1950 2875);
FORCEADD OFFPAGE..4
(-2150 2600);
FORCEPROP 2 LAST $XR0 141 
J 0
(-1964 2600);
DISPLAY 0.638298 (-1964 2600);
PAINT MONO (-1964 2600);
FORCEPROP 1 LAST COMMENT_BODY TRUE
J 0
(-2175 2500);
DISPLAY 0.872340 (-2175 2500);
PAINT GREEN (-2175 2500);
DISPLAY INVISIBLE (-2175 2500);
FORCEPROP 2 LAST CDS_LIB mstr_standard
J 0
(-2150 2600);
PAINT ORANGE (-2150 2600);
DISPLAY INVISIBLE (-2150 2600);
FORCEPROP 1 LAST OFFPAGE TRUE
J 0
(-1825 2475);
DISPLAY 0.872340 (-1825 2475);
PAINT GREEN (-1825 2475);
DISPLAY INVISIBLE (-1825 2475);
FORCEPROP 2 LAST PATH I45
J 0
(-1950 2675);
DISPLAY 1.021277 (-1950 2675);
PAINT ORANGE (-1950 2675);
DISPLAY INVISIBLE (-1950 2675);
FORCEADD CAP_A..1
(-5925 1250);
FORCEPROP 1 LASTPIN (-5925 1350) $PN 1
J 0
(-5915 1330);
DISPLAY 0.617021 (-5915 1330);
PAINT ORANGE (-5915 1330);
FORCEPROP 1 LASTPIN (-5925 1150) $PN 2
J 0
(-5915 1130);
DISPLAY 0.617021 (-5915 1130);
PAINT ORANGE (-5915 1130);
FORCEPROP 1 LAST VOLTAGE 16V
J 0
(-5875 1250);
DISPLAY 0.617021 (-5875 1250);
PAINT SKYBLUE (-5875 1250);
FORCEPROP 1 LAST MATERIAL X7R
J 0
(-5875 1150);
DISPLAY 0.617021 (-5875 1150);
PAINT SKYBLUE (-5875 1150);
FORCEPROP 1 LAST LOCATION C9G4
J 0
(-5875 1350);
DISPLAY 0.617021 (-5875 1350);
PAINT AQUA (-5875 1350);
FORCEPROP 1 LAST VALUE 0.1UF
J 0
(-5875 1300);
DISPLAY 0.617021 (-5875 1300);
PAINT SKYBLUE (-5875 1300);
FORCEPROP 1 LAST TOLERANCE 10%
J 0
(-5875 1200);
DISPLAY 0.617021 (-5875 1200);
PAINT SKYBLUE (-5875 1200);
FORCEPROP 1 LAST PACK_TYPE 0402V
J 0
(-5875 1050);
DISPLAY 0.617021 (-5875 1050);
PAINT SKYBLUE (-5875 1050);
FORCEPROP 1 LAST PART_NUMBER A36096-030
J 0
(-5875 1100);
DISPLAY 0.617021 (-5875 1100);
PAINT BLUE (-5875 1100);
FORCEPROP 2 LAST CDS_LIB dev_discrete
J 0
(-5925 1250);
PAINT ORANGE (-5925 1250);
DISPLAY INVISIBLE (-5925 1250);
FORCEPROP 1 LAST PATH I46
J 0
(-5875 1400);
DISPLAY 0.978723 (-5875 1400);
PAINT WHITE (-5875 1400);
DISPLAY INVISIBLE (-5875 1400);
FORCEPROP 2 LAST ROOM NIC_SPRV
J 0
(-5875 1400);
DISPLAY 1.021277 (-5875 1400);
PAINT ORANGE (-5875 1400);
DISPLAY INVISIBLE (-5875 1400);
FORCEPROP 2 LAST CDS_LOCATION C9G4
J 0
(-5875 1350);
DISPLAY 0.617021 (-5875 1350);
PAINT AQUA (-5875 1350);
DISPLAY INVISIBLE (-5875 1350);
FORCEPROP 2 LAST BOM_COST NT_GBE_BASE
J 0
(-5875 1450);
DISPLAY 1.021277 (-5875 1450);
PAINT ORANGE (-5875 1450);
DISPLAY INVISIBLE (-5875 1450);
FORCEPROP 2 LAST CDS_SEC 1
J 0
(-5875 1400);
PAINT ORANGE (-5875 1400);
DISPLAY INVISIBLE (-5875 1400);
FORCEPROP 2 LAST SEC_TYPE 0402V
J 0
(-5875 1450);
DISPLAY 1.021277 (-5875 1450);
PAINT ORANGE (-5875 1450);
DISPLAY INVISIBLE (-5875 1450);
FORCEPROP 2 LAST SEC 1
J 0
(-5875 1450);
PAINT MONO (-5875 1450);
DISPLAY INVISIBLE (-5875 1450);
FORCEADD CAP_A..1
(-6250 1250);
FORCEPROP 1 LASTPIN (-6250 1150) $PN 2
J 0
(-6240 1130);
DISPLAY 0.617021 (-6240 1130);
PAINT ORANGE (-6240 1130);
FORCEPROP 1 LASTPIN (-6250 1350) $PN 1
J 0
(-6240 1330);
DISPLAY 0.617021 (-6240 1330);
PAINT ORANGE (-6240 1330);
FORCEPROP 1 LAST LOCATION C9G6
J 0
(-6200 1350);
DISPLAY 0.617021 (-6200 1350);
PAINT AQUA (-6200 1350);
FORCEPROP 1 LAST PART_NUMBER A36096-030
J 0
(-6200 1100);
DISPLAY 0.617021 (-6200 1100);
PAINT BLUE (-6200 1100);
FORCEPROP 1 LAST VALUE 0.1UF
J 0
(-6200 1300);
DISPLAY 0.617021 (-6200 1300);
PAINT SKYBLUE (-6200 1300);
FORCEPROP 1 LAST TOLERANCE 10%
J 0
(-6200 1200);
DISPLAY 0.617021 (-6200 1200);
PAINT SKYBLUE (-6200 1200);
FORCEPROP 1 LAST PACK_TYPE 0402V
J 0
(-6200 1050);
DISPLAY 0.617021 (-6200 1050);
PAINT SKYBLUE (-6200 1050);
FORCEPROP 1 LAST VOLTAGE 16V
J 0
(-6200 1250);
DISPLAY 0.617021 (-6200 1250);
PAINT SKYBLUE (-6200 1250);
FORCEPROP 1 LAST MATERIAL X7R
J 0
(-6200 1150);
DISPLAY 0.617021 (-6200 1150);
PAINT SKYBLUE (-6200 1150);
FORCEPROP 2 LAST CDS_LIB dev_discrete
J 0
(-6250 1250);
PAINT ORANGE (-6250 1250);
DISPLAY INVISIBLE (-6250 1250);
FORCEPROP 2 LAST CDS_LOCATION C9G6
J 0
(-6200 1350);
DISPLAY 0.617021 (-6200 1350);
PAINT AQUA (-6200 1350);
DISPLAY INVISIBLE (-6200 1350);
FORCEPROP 2 LAST CDS_SEC 1
J 0
(-6200 1400);
PAINT ORANGE (-6200 1400);
DISPLAY INVISIBLE (-6200 1400);
FORCEPROP 2 LAST ROOM NIC_SPRV
J 0
(-6200 1400);
DISPLAY 1.021277 (-6200 1400);
PAINT ORANGE (-6200 1400);
DISPLAY INVISIBLE (-6200 1400);
FORCEPROP 1 LAST PATH I47
J 0
(-6200 1400);
DISPLAY 0.978723 (-6200 1400);
PAINT WHITE (-6200 1400);
DISPLAY INVISIBLE (-6200 1400);
FORCEPROP 2 LAST BOM_COST NT_GBE_BASE
J 0
(-6200 1450);
DISPLAY 1.021277 (-6200 1450);
PAINT ORANGE (-6200 1450);
DISPLAY INVISIBLE (-6200 1450);
FORCEPROP 2 LAST SEC_TYPE 0402V
J 0
(-6200 1450);
DISPLAY 1.021277 (-6200 1450);
PAINT ORANGE (-6200 1450);
DISPLAY INVISIBLE (-6200 1450);
FORCEPROP 2 LAST SEC 1
J 0
(-6200 1450);
PAINT MONO (-6200 1450);
DISPLAY INVISIBLE (-6200 1450);
FORCEADD CAP..1
(-6600 1250);
FORCEPROP 1 LASTPIN (-6600 1150) $PN 2
J 0
(-6590 1130);
DISPLAY 0.617021 (-6590 1130);
PAINT ORANGE (-6590 1130);
FORCEPROP 1 LAST TOLERANCE 10%
J 0
(-6550 1200);
DISPLAY 0.617021 (-6550 1200);
PAINT SKYBLUE (-6550 1200);
FORCEPROP 1 LAST PACK_TYPE 0402
J 0
(-6550 1050);
DISPLAY 0.617021 (-6550 1050);
PAINT SKYBLUE (-6550 1050);
FORCEPROP 1 LAST VOLTAGE 16V
J 0
(-6550 1250);
DISPLAY 0.617021 (-6550 1250);
PAINT SKYBLUE (-6550 1250);
FORCEPROP 1 LAST MATERIAL X7S
J 0
(-6550 1150);
DISPLAY 0.617021 (-6550 1150);
PAINT SKYBLUE (-6550 1150);
FORCEPROP 1 LASTPIN (-6600 1350) $PN 1
J 0
(-6590 1330);
DISPLAY 0.617021 (-6590 1330);
PAINT ORANGE (-6590 1330);
FORCEPROP 1 LAST VALUE 1.0UF
J 0
(-6550 1300);
DISPLAY 0.617021 (-6550 1300);
PAINT SKYBLUE (-6550 1300);
FORCEPROP 1 LAST LOCATION C9G5
J 0
(-6550 1350);
DISPLAY 0.617021 (-6550 1350);
PAINT AQUA (-6550 1350);
FORCEPROP 1 LAST PART_NUMBER G71842-007
J 0
(-6550 1100);
DISPLAY 0.617021 (-6550 1100);
PAINT BLUE (-6550 1100);
FORCEPROP 2 LAST CDS_LIB mstr_discrete
J 0
(-6600 1250);
PAINT ORANGE (-6600 1250);
DISPLAY INVISIBLE (-6600 1250);
FORCEPROP 2 LAST BOM_COST NT_GBE_BASE
J 0
(-6550 1450);
DISPLAY 1.021277 (-6550 1450);
PAINT ORANGE (-6550 1450);
DISPLAY INVISIBLE (-6550 1450);
FORCEPROP 2 LAST SEC_TYPE 0402
J 0
(-6550 1450);
DISPLAY 1.021277 (-6550 1450);
PAINT ORANGE (-6550 1450);
DISPLAY INVISIBLE (-6550 1450);
FORCEPROP 2 LAST SEC 1
J 0
(-6550 1450);
PAINT MONO (-6550 1450);
DISPLAY INVISIBLE (-6550 1450);
FORCEPROP 2 LAST CDS_LOCATION C9G5
J 0
(-6550 1350);
DISPLAY 0.617021 (-6550 1350);
PAINT AQUA (-6550 1350);
DISPLAY INVISIBLE (-6550 1350);
FORCEPROP 1 LAST PATH I48
J 0
(-6550 1400);
DISPLAY 0.978723 (-6550 1400);
PAINT WHITE (-6550 1400);
DISPLAY INVISIBLE (-6550 1400);
FORCEPROP 2 LAST ROOM NIC_SPRV
J 0
(-6550 1400);
DISPLAY 1.021277 (-6550 1400);
PAINT ORANGE (-6550 1400);
DISPLAY INVISIBLE (-6550 1400);
FORCEADD OFFPAGE..2
(-5350 1500);
FORCEPROP 2 LAST $XR0 141 
J 0
(-5161 1500);
DISPLAY 0.638298 (-5161 1500);
PAINT MONO (-5161 1500);
FORCEPROP 1 LAST COMMENT_BODY TRUE
J 0
(-5395 1405);
DISPLAY 0.872340 (-5395 1405);
PAINT GREEN (-5395 1405);
DISPLAY INVISIBLE (-5395 1405);
FORCEPROP 2 LAST CDS_LIB mstr_standard
J 0
(-5350 1500);
PAINT ORANGE (-5350 1500);
DISPLAY INVISIBLE (-5350 1500);
FORCEPROP 2 LAST PATH I49
J 0
(-5300 1575);
DISPLAY 1.021277 (-5300 1575);
PAINT ORANGE (-5300 1575);
DISPLAY INVISIBLE (-5300 1575);
FORCEPROP 1 LAST OFFPAGE TRUE
J 0
(-5025 1375);
DISPLAY 0.872340 (-5025 1375);
PAINT GREEN (-5025 1375);
DISPLAY INVISIBLE (-5025 1375);
FORCEADD GND..1
(-6600 950);
FORCEPROP 3 LASTPIN (-6600 1000) SIG_NAME GND\g
J 0
(-6590 1010);
DISPLAY 0.659574 (-6590 1010);
PAINT MONO (-6590 1010);
DISPLAY INVISIBLE (-6590 1010);
FORCEPROP 1 LAST VOLTAGE 0.0V
J 0
(-6645 907);
DISPLAY 0.340426 (-6645 907);
PAINT SKYBLUE (-6645 907);
DISPLAY INVISIBLE (-6645 907);
FORCEPROP 2 LAST CDS_LIB mstr_symbols
J 0
(-6600 950);
PAINT ORANGE (-6600 950);
DISPLAY INVISIBLE (-6600 950);
FORCEPROP 1 LAST SIZE 1B
J 0
(-6525 900);
DISPLAY 0.872340 (-6525 900);
PAINT AQUA (-6525 900);
DISPLAY INVISIBLE (-6525 900);
FORCEPROP 1 LAST BODY_TYPE PLUMBING
J 0
(-6645 907);
DISPLAY 0.340426 (-6645 907);
PAINT GREEN (-6645 907);
DISPLAY INVISIBLE (-6645 907);
FORCEPROP 1 LAST PATH I50
J 0
(-6525 950);
DISPLAY 0.872340 (-6525 950);
PAINT AQUA (-6525 950);
DISPLAY INVISIBLE (-6525 950);
FORCEPROP 1 LAST HDL_POWER GND
J 0
(-6600 1100);
DISPLAY 0.872340 (-6600 1100);
PAINT GREEN (-6600 1100);
DISPLAY INVISIBLE (-6600 1100);
FORCEADD OFFPAGE..1
(-5075 2150);
FORCEPROP 2 LAST $XR0 139 
J 0
(-5357 2150);
DISPLAY 0.638298 (-5357 2150);
PAINT MONO (-5357 2150);
FORCEPROP 1 LAST OFFPAGE TRUE
J 0
(-4750 2025);
DISPLAY 0.872340 (-4750 2025);
PAINT GREEN (-4750 2025);
DISPLAY INVISIBLE (-4750 2025);
FORCEPROP 2 LAST PATH I53
J 0
(-5325 2200);
DISPLAY 1.021277 (-5325 2200);
PAINT ORANGE (-5325 2200);
DISPLAY INVISIBLE (-5325 2200);
FORCEPROP 2 LAST CDS_LIB mstr_standard
J 0
(-5075 2150);
PAINT ORANGE (-5075 2150);
DISPLAY INVISIBLE (-5075 2150);
FORCEPROP 1 LAST COMMENT_BODY TRUE
J 0
(-4950 2050);
DISPLAY 0.872340 (-4950 2050);
PAINT GREEN (-4950 2050);
DISPLAY INVISIBLE (-4950 2050);
FORCEADD RES..1
(-4550 2150);
FORCEPROP 1 LAST MATERIAL CHIP
J 0
(-4800 2100);
DISPLAY 0.617021 (-4800 2100);
PAINT SKYBLUE (-4800 2100);
FORCEPROP 1 LASTPIN (-4650 2150) $PN 1
J 0
(-4638 2162);
DISPLAY 0.617021 (-4638 2162);
PAINT ORANGE (-4638 2162);
FORCEPROP 1 LAST WATTAGE 1/16W
J 2
(-4575 2100);
DISPLAY 0.617021 (-4575 2100);
PAINT SKYBLUE (-4575 2100);
FORCEPROP 1 LAST LOCATION R9G1
J 0
(-4600 2200);
DISPLAY 0.617021 (-4600 2200);
PAINT AQUA (-4600 2200);
FORCEPROP 1 LASTPIN (-4450 2150) $PN 2
J 0
(-4488 2162);
DISPLAY 0.617021 (-4488 2162);
PAINT ORANGE (-4488 2162);
FORCEPROP 1 LAST PACK_TYPE 0402
J 0
(-4475 2100);
DISPLAY 0.617021 (-4475 2100);
PAINT SKYBLUE (-4475 2100);
FORCEPROP 1 LAST TOLERANCE 1%
J 0
(-4375 2100);
DISPLAY 0.617021 (-4375 2100);
PAINT SKYBLUE (-4375 2100);
FORCEPROP 1 LAST PART_NUMBER G21796-009
J 0
(-4550 2050);
DISPLAY 0.617021 (-4550 2050);
PAINT BLUE (-4550 2050);
FORCEPROP 1 LAST VALUE 150.0
J 2
(-4200 2100);
DISPLAY 0.617021 (-4200 2100);
PAINT SKYBLUE (-4200 2100);
FORCEPROP 2 LAST ROOM NIC_SPRV
J 0
(-4600 2250);
DISPLAY 1.021277 (-4600 2250);
PAINT ORANGE (-4600 2250);
DISPLAY INVISIBLE (-4600 2250);
FORCEPROP 2 LAST CDS_LOCATION R9G1
J 0
(-4600 2200);
DISPLAY 0.617021 (-4600 2200);
PAINT AQUA (-4600 2200);
DISPLAY INVISIBLE (-4600 2200);
FORCEPROP 2 LAST CDS_LIB mstr_discrete
J 0
(-4550 2150);
PAINT ORANGE (-4550 2150);
DISPLAY INVISIBLE (-4550 2150);
FORCEPROP 2 LAST BOM_COST NT_GBE_BASE
J 0
(-4600 2300);
DISPLAY 1.021277 (-4600 2300);
PAINT ORANGE (-4600 2300);
DISPLAY INVISIBLE (-4600 2300);
FORCEPROP 1 LAST PATH I54
J 0
(-4600 2300);
DISPLAY 0.978723 (-4600 2300);
PAINT WHITE (-4600 2300);
DISPLAY INVISIBLE (-4600 2300);
FORCEPROP 2 LAST SEC 1
J 0
(-4600 2350);
DISPLAY 0.680851 (-4600 2350);
PAINT MONO (-4600 2350);
DISPLAY INVISIBLE (-4600 2350);
FORCEPROP 2 LAST SEC_TYPE 0402
J 0
(-4600 2350);
DISPLAY 1.021277 (-4600 2350);
PAINT ORANGE (-4600 2350);
DISPLAY INVISIBLE (-4600 2350);
FORCEADD RES..1
(-1925 1175);
FORCEPROP 1 LAST WATTAGE 1/16W
J 2
(-1950 1025);
DISPLAY 0.617021 (-1950 1025);
PAINT SKYBLUE (-1950 1025);
FORCEPROP 1 LAST VALUE 0.0
J 2
(-1950 1075);
DISPLAY 0.617021 (-1950 1075);
PAINT SKYBLUE (-1950 1075);
FORCEPROP 1 LASTPIN (-2025 1175) $PN 1
J 0
(-2013 1187);
DISPLAY 0.617021 (-2013 1187);
PAINT ORANGE (-2013 1187);
FORCEPROP 1 LAST TOLERANCE 5%
J 0
(-1925 1075);
DISPLAY 0.617021 (-1925 1075);
PAINT SKYBLUE (-1925 1075);
FORCEPROP 1 LAST MATERIAL CHIP
J 0
(-1925 1025);
DISPLAY 0.617021 (-1925 1025);
PAINT SKYBLUE (-1925 1025);
FORCEPROP 1 LAST LOCATION R9G4
J 0
(-1975 1225);
DISPLAY 0.617021 (-1975 1225);
PAINT AQUA (-1975 1225);
FORCEPROP 1 LASTPIN (-1825 1175) $PN 2
J 0
(-1863 1187);
DISPLAY 0.617021 (-1863 1187);
PAINT ORANGE (-1863 1187);
FORCEPROP 1 LAST PART_NUMBER G21497-005
J 0
(-1975 1275);
DISPLAY 0.617021 (-1975 1275);
PAINT BLUE (-1975 1275);
FORCEPROP 1 LAST PACK_TYPE 0402
J 0
(-1675 1025);
DISPLAY 0.617021 (-1675 1025);
PAINT SKYBLUE (-1675 1025);
FORCEPROP 2 LAST CDS_LIB mstr_discrete
J 0
(-1925 1175);
PAINT ORANGE (-1925 1175);
DISPLAY INVISIBLE (-1925 1175);
FORCEPROP 2 LAST CDS_LOCATION R9G4
J 0
(-1975 1225);
DISPLAY 0.617021 (-1975 1225);
PAINT AQUA (-1975 1225);
DISPLAY INVISIBLE (-1975 1225);
FORCEPROP 2 LAST SEC 1
J 0
(-1975 1375);
PAINT MONO (-1975 1375);
DISPLAY INVISIBLE (-1975 1375);
FORCEPROP 1 LAST PATH I56
J 0
(-1975 1325);
DISPLAY 0.978723 (-1975 1325);
PAINT WHITE (-1975 1325);
DISPLAY INVISIBLE (-1975 1325);
FORCEPROP 2 LAST ROOM NIC_SPRV
J 0
(-1975 1325);
DISPLAY 1.021277 (-1975 1325);
PAINT ORANGE (-1975 1325);
DISPLAY INVISIBLE (-1975 1325);
FORCEPROP 2 LAST SEC_TYPE 0402
J 0
(-1975 1375);
DISPLAY 1.021277 (-1975 1375);
PAINT ORANGE (-1975 1375);
DISPLAY INVISIBLE (-1975 1375);
FORCEPROP 2 LAST BOM_COST NT_GBE_BASE
J 0
(-1975 1375);
DISPLAY 1.021277 (-1975 1375);
PAINT ORANGE (-1975 1375);
DISPLAY INVISIBLE (-1975 1375);
FORCEADD CAP..1
(-2050 2050);
FORCEPROP 1 LAST TOLERANCE 10%
J 0
(-2000 2000);
DISPLAY 0.617021 (-2000 2000);
PAINT SKYBLUE (-2000 2000);
FORCEPROP 1 LAST PACK_TYPE 0402LF
J 0
(-2000 1850);
DISPLAY 0.617021 (-2000 1850);
PAINT SKYBLUE (-2000 1850);
FORCEPROP 1 LAST MATERIAL X7R
J 0
(-2000 1950);
DISPLAY 0.617021 (-2000 1950);
PAINT SKYBLUE (-2000 1950);
FORCEPROP 1 LASTPIN (-2050 1950) $PN 2
J 0
(-2040 1930);
DISPLAY 0.617021 (-2040 1930);
PAINT ORANGE (-2040 1930);
FORCEPROP 1 LAST PART_NUMBER A36096-049
J 0
(-2000 1900);
DISPLAY 0.617021 (-2000 1900);
PAINT BLUE (-2000 1900);
FORCEPROP 1 LASTPIN (-2050 2150) $PN 1
J 0
(-2040 2130);
DISPLAY 0.617021 (-2040 2130);
PAINT ORANGE (-2040 2130);
FORCEPROP 1 LAST VOLTAGE 50V
J 0
(-2000 2050);
DISPLAY 0.617021 (-2000 2050);
PAINT SKYBLUE (-2000 2050);
FORCEPROP 1 LAST VALUE 470PF
J 0
(-2000 2100);
DISPLAY 0.617021 (-2000 2100);
PAINT SKYBLUE (-2000 2100);
FORCEPROP 1 LAST LOCATION C9G1
J 0
(-2000 2150);
DISPLAY 0.617021 (-2000 2150);
PAINT AQUA (-2000 2150);
FORCEPROP 2 LAST CDS_LIB mstr_discrete
J 0
(-2050 2050);
PAINT ORANGE (-2050 2050);
DISPLAY INVISIBLE (-2050 2050);
FORCEPROP 2 LAST ROOM NIC_SPRV
J 0
(-2000 2200);
DISPLAY 1.021277 (-2000 2200);
PAINT ORANGE (-2000 2200);
DISPLAY INVISIBLE (-2000 2200);
FORCEPROP 1 LAST PATH I58
J 0
(-2000 2200);
DISPLAY 0.978723 (-2000 2200);
PAINT WHITE (-2000 2200);
DISPLAY INVISIBLE (-2000 2200);
FORCEPROP 2 LAST CDS_LOCATION C9G1
J 0
(-2000 2150);
DISPLAY 0.617021 (-2000 2150);
PAINT AQUA (-2000 2150);
DISPLAY INVISIBLE (-2000 2150);
FORCEPROP 2 LAST SEC 1
J 0
(-2000 2250);
PAINT MONO (-2000 2250);
DISPLAY INVISIBLE (-2000 2250);
FORCEPROP 2 LAST BOM_COST NT_GBE_BASE
J 0
(-2000 2250);
DISPLAY 1.021277 (-2000 2250);
PAINT ORANGE (-2000 2250);
DISPLAY INVISIBLE (-2000 2250);
FORCEPROP 2 LAST SEC_TYPE 0402LF
J 0
(-2000 2250);
DISPLAY 1.021277 (-2000 2250);
PAINT ORANGE (-2000 2250);
DISPLAY INVISIBLE (-2000 2250);
FORCEADD CAP..1
(-1750 2050);
FORCEPROP 1 LAST MATERIAL X7R
J 0
(-1700 1950);
DISPLAY 0.617021 (-1700 1950);
PAINT SKYBLUE (-1700 1950);
FORCEPROP 1 LAST TOLERANCE 10%
J 0
(-1700 2000);
DISPLAY 0.617021 (-1700 2000);
PAINT SKYBLUE (-1700 2000);
FORCEPROP 1 LASTPIN (-1750 1950) $PN 2
J 0
(-1740 1930);
DISPLAY 0.617021 (-1740 1930);
PAINT ORANGE (-1740 1930);
FORCEPROP 1 LAST PART_NUMBER A36096-049
J 0
(-1700 1900);
DISPLAY 0.617021 (-1700 1900);
PAINT BLUE (-1700 1900);
FORCEPROP 1 LAST PACK_TYPE 0402LF
J 0
(-1700 1850);
DISPLAY 0.617021 (-1700 1850);
PAINT SKYBLUE (-1700 1850);
FORCEPROP 1 LAST LOCATION C9G3
J 0
(-1700 2150);
DISPLAY 0.617021 (-1700 2150);
PAINT AQUA (-1700 2150);
FORCEPROP 1 LAST VALUE 470PF
J 0
(-1700 2100);
DISPLAY 0.617021 (-1700 2100);
PAINT SKYBLUE (-1700 2100);
FORCEPROP 1 LAST VOLTAGE 50V
J 0
(-1700 2050);
DISPLAY 0.617021 (-1700 2050);
PAINT SKYBLUE (-1700 2050);
FORCEPROP 1 LASTPIN (-1750 2150) $PN 1
J 0
(-1740 2130);
DISPLAY 0.617021 (-1740 2130);
PAINT ORANGE (-1740 2130);
FORCEPROP 2 LAST SEC_TYPE 0402LF
J 0
(-1700 2250);
DISPLAY 1.021277 (-1700 2250);
PAINT ORANGE (-1700 2250);
DISPLAY INVISIBLE (-1700 2250);
FORCEPROP 2 LAST CDS_LOCATION C9G3
J 0
(-1700 2150);
DISPLAY 0.617021 (-1700 2150);
PAINT AQUA (-1700 2150);
DISPLAY INVISIBLE (-1700 2150);
FORCEPROP 1 LAST PATH I59
J 0
(-1700 2200);
DISPLAY 0.978723 (-1700 2200);
PAINT WHITE (-1700 2200);
DISPLAY INVISIBLE (-1700 2200);
FORCEPROP 2 LAST SEC 1
J 0
(-1700 2250);
PAINT MONO (-1700 2250);
DISPLAY INVISIBLE (-1700 2250);
FORCEPROP 2 LAST BOM_COST NT_GBE_BASE
J 0
(-1700 2250);
DISPLAY 1.021277 (-1700 2250);
PAINT ORANGE (-1700 2250);
DISPLAY INVISIBLE (-1700 2250);
FORCEPROP 2 LAST CDS_LIB mstr_discrete
J 0
(-1750 2050);
PAINT ORANGE (-1750 2050);
DISPLAY INVISIBLE (-1750 2050);
FORCEPROP 2 LAST ROOM NIC_SPRV
J 0
(-1700 2200);
DISPLAY 1.021277 (-1700 2200);
PAINT ORANGE (-1700 2200);
DISPLAY INVISIBLE (-1700 2200);
FORCEADD CAP..1
(-4800 1950);
FORCEPROP 1 LAST TOLERANCE 10%
J 0
(-4750 1900);
DISPLAY 0.617021 (-4750 1900);
PAINT SKYBLUE (-4750 1900);
FORCEPROP 1 LAST VOLTAGE 50V
J 0
(-4750 1950);
DISPLAY 0.617021 (-4750 1950);
PAINT SKYBLUE (-4750 1950);
FORCEPROP 1 LAST MATERIAL X7R
J 0
(-4750 1850);
DISPLAY 0.617021 (-4750 1850);
PAINT SKYBLUE (-4750 1850);
FORCEPROP 1 LASTPIN (-4800 1850) $PN 2
J 0
(-4790 1830);
DISPLAY 0.617021 (-4790 1830);
PAINT ORANGE (-4790 1830);
FORCEPROP 1 LAST PART_NUMBER A36096-049
J 0
(-4750 1800);
DISPLAY 0.617021 (-4750 1800);
PAINT BLUE (-4750 1800);
FORCEPROP 1 LAST VALUE 470PF
J 0
(-4750 2000);
DISPLAY 0.617021 (-4750 2000);
PAINT SKYBLUE (-4750 2000);
FORCEPROP 1 LAST PACK_TYPE 0402LF
J 0
(-4750 1750);
DISPLAY 0.617021 (-4750 1750);
PAINT SKYBLUE (-4750 1750);
FORCEPROP 1 LASTPIN (-4800 2050) $PN 1
J 0
(-4790 2030);
DISPLAY 0.617021 (-4790 2030);
PAINT ORANGE (-4790 2030);
FORCEPROP 1 LAST LOCATION C9F22
J 0
(-4750 2050);
DISPLAY 0.617021 (-4750 2050);
PAINT AQUA (-4750 2050);
FORCEPROP 2 LAST CDS_LIB mstr_discrete
J 0
(-4800 1950);
PAINT ORANGE (-4800 1950);
DISPLAY INVISIBLE (-4800 1950);
FORCEPROP 2 LAST ROOM NIC_SPRV
J 0
(-4750 2100);
DISPLAY 1.021277 (-4750 2100);
PAINT ORANGE (-4750 2100);
DISPLAY INVISIBLE (-4750 2100);
FORCEPROP 1 LAST PATH I60
J 0
(-4750 2100);
DISPLAY 0.978723 (-4750 2100);
PAINT WHITE (-4750 2100);
DISPLAY INVISIBLE (-4750 2100);
FORCEPROP 2 LAST CDS_LOCATION C9F22
J 0
(-4750 2050);
DISPLAY 0.617021 (-4750 2050);
PAINT AQUA (-4750 2050);
DISPLAY INVISIBLE (-4750 2050);
FORCEPROP 2 LAST SEC 1
J 0
(-4750 2150);
PAINT MONO (-4750 2150);
DISPLAY INVISIBLE (-4750 2150);
FORCEPROP 2 LAST SEC_TYPE 0402LF
J 0
(-4750 2150);
DISPLAY 1.021277 (-4750 2150);
PAINT ORANGE (-4750 2150);
DISPLAY INVISIBLE (-4750 2150);
FORCEPROP 2 LAST BOM_COST NT_GBE_BASE
J 0
(-4750 2150);
DISPLAY 1.021277 (-4750 2150);
PAINT ORANGE (-4750 2150);
DISPLAY INVISIBLE (-4750 2150);
FORCEADD GND..1
(-4800 1725);
FORCEPROP 3 LASTPIN (-4800 1775) SIG_NAME GND\g
J 0
(-4790 1785);
DISPLAY 0.659574 (-4790 1785);
PAINT MONO (-4790 1785);
DISPLAY INVISIBLE (-4790 1785);
FORCEPROP 1 LAST VOLTAGE 0.0V
J 0
(-4845 1682);
DISPLAY 0.340426 (-4845 1682);
PAINT SKYBLUE (-4845 1682);
DISPLAY INVISIBLE (-4845 1682);
FORCEPROP 1 LAST SIZE 1B
J 0
(-4725 1675);
DISPLAY 0.872340 (-4725 1675);
PAINT AQUA (-4725 1675);
DISPLAY INVISIBLE (-4725 1675);
FORCEPROP 2 LAST CDS_LIB mstr_symbols
J 0
(-4800 1725);
PAINT ORANGE (-4800 1725);
DISPLAY INVISIBLE (-4800 1725);
FORCEPROP 1 LAST BODY_TYPE PLUMBING
J 0
(-4845 1682);
DISPLAY 0.340426 (-4845 1682);
PAINT GREEN (-4845 1682);
DISPLAY INVISIBLE (-4845 1682);
FORCEPROP 1 LAST PATH I61
J 0
(-4725 1725);
DISPLAY 0.872340 (-4725 1725);
PAINT AQUA (-4725 1725);
DISPLAY INVISIBLE (-4725 1725);
FORCEPROP 1 LAST HDL_POWER GND
J 0
(-4800 1875);
DISPLAY 0.872340 (-4800 1875);
PAINT GREEN (-4800 1875);
DISPLAY INVISIBLE (-4800 1875);
FORCEADD GND..1
(-2050 1700);
FORCEPROP 3 LASTPIN (-2050 1750) SIG_NAME GND\g
J 0
(-2040 1760);
DISPLAY 0.659574 (-2040 1760);
PAINT MONO (-2040 1760);
DISPLAY INVISIBLE (-2040 1760);
FORCEPROP 1 LAST BODY_TYPE PLUMBING
J 0
(-2095 1657);
DISPLAY 0.340426 (-2095 1657);
PAINT GREEN (-2095 1657);
DISPLAY INVISIBLE (-2095 1657);
FORCEPROP 2 LAST CDS_LIB mstr_symbols
J 0
(-2050 1700);
PAINT ORANGE (-2050 1700);
DISPLAY INVISIBLE (-2050 1700);
FORCEPROP 1 LAST VOLTAGE 0.0V
J 0
(-2095 1657);
DISPLAY 0.340426 (-2095 1657);
PAINT SKYBLUE (-2095 1657);
DISPLAY INVISIBLE (-2095 1657);
FORCEPROP 1 LAST HDL_POWER GND
J 0
(-2050 1850);
DISPLAY 0.872340 (-2050 1850);
PAINT GREEN (-2050 1850);
DISPLAY INVISIBLE (-2050 1850);
FORCEPROP 1 LAST SIZE 1B
J 0
(-1975 1650);
DISPLAY 0.872340 (-1975 1650);
PAINT AQUA (-1975 1650);
DISPLAY INVISIBLE (-1975 1650);
FORCEPROP 1 LAST PATH I62
J 0
(-1975 1700);
DISPLAY 0.872340 (-1975 1700);
PAINT AQUA (-1975 1700);
DISPLAY INVISIBLE (-1975 1700);
FORCEADD GND..1
(-1750 1700);
FORCEPROP 3 LASTPIN (-1750 1750) SIG_NAME GND\g
J 0
(-1740 1760);
DISPLAY 0.659574 (-1740 1760);
PAINT MONO (-1740 1760);
DISPLAY INVISIBLE (-1740 1760);
FORCEPROP 1 LAST BODY_TYPE PLUMBING
J 0
(-1795 1657);
DISPLAY 0.340426 (-1795 1657);
PAINT GREEN (-1795 1657);
DISPLAY INVISIBLE (-1795 1657);
FORCEPROP 1 LAST VOLTAGE 0.0V
J 0
(-1795 1657);
DISPLAY 0.340426 (-1795 1657);
PAINT SKYBLUE (-1795 1657);
DISPLAY INVISIBLE (-1795 1657);
FORCEPROP 2 LAST CDS_LIB mstr_symbols
J 0
(-1750 1700);
PAINT ORANGE (-1750 1700);
DISPLAY INVISIBLE (-1750 1700);
FORCEPROP 1 LAST SIZE 1B
J 0
(-1675 1650);
DISPLAY 0.872340 (-1675 1650);
PAINT AQUA (-1675 1650);
DISPLAY INVISIBLE (-1675 1650);
FORCEPROP 1 LAST PATH I63
J 0
(-1675 1700);
DISPLAY 0.872340 (-1675 1700);
PAINT AQUA (-1675 1700);
DISPLAY INVISIBLE (-1675 1700);
FORCEPROP 1 LAST HDL_POWER GND
J 0
(-1750 1850);
DISPLAY 0.872340 (-1750 1850);
PAINT GREEN (-1750 1850);
DISPLAY INVISIBLE (-1750 1850);
FORCEADD P3V3_STBY..1
(-5575 2675);
FORCEPROP 3 LASTPIN (-5575 2625) SIG_NAME P3V3_STBY\g
J 0
(-5565 2635);
DISPLAY 0.659574 (-5565 2635);
PAINT MONO (-5565 2635);
DISPLAY INVISIBLE (-5565 2635);
FORCEPROP 1 LAST HDL_POWER P3V3_STBY
J 0
(-5875 2550);
DISPLAY 0.872340 (-5875 2550);
PAINT ORANGE (-5875 2550);
DISPLAY INVISIBLE (-5875 2550);
FORCEPROP 1 LAST VOLTAGE 3.3V
J 0
(-5620 2632);
DISPLAY 0.340426 (-5620 2632);
PAINT SKYBLUE (-5620 2632);
DISPLAY INVISIBLE (-5620 2632);
FORCEPROP 1 LAST SIZE 1B
J 0
(-5530 2697);
DISPLAY 0.340426 (-5530 2697);
PAINT GREEN (-5530 2697);
DISPLAY INVISIBLE (-5530 2697);
FORCEPROP 2 LAST CDS_LIB mstr_symbols
J 0
(-5575 2675);
PAINT ORANGE (-5575 2675);
DISPLAY INVISIBLE (-5575 2675);
FORCEPROP 1 LAST BODY_TYPE PLUMBING
J 0
(-5620 2632);
DISPLAY 0.340426 (-5620 2632);
PAINT GREEN (-5620 2632);
DISPLAY INVISIBLE (-5620 2632);
FORCEPROP 1 LAST PATH I64
J 0
(-5530 2677);
DISPLAY 0.340426 (-5530 2677);
PAINT GREEN (-5530 2677);
DISPLAY INVISIBLE (-5530 2677);
FORCEADD P3V3_STBY..1
(-1700 1425);
FORCEPROP 3 LASTPIN (-1700 1375) SIG_NAME P3V3_STBY\g
J 0
(-1690 1385);
DISPLAY 0.659574 (-1690 1385);
PAINT MONO (-1690 1385);
DISPLAY INVISIBLE (-1690 1385);
FORCEPROP 1 LAST HDL_POWER P3V3_STBY
J 0
(-2000 1300);
DISPLAY 0.872340 (-2000 1300);
PAINT ORANGE (-2000 1300);
DISPLAY INVISIBLE (-2000 1300);
FORCEPROP 1 LAST PATH I65
J 0
(-1655 1427);
DISPLAY 0.340426 (-1655 1427);
PAINT GREEN (-1655 1427);
DISPLAY INVISIBLE (-1655 1427);
FORCEPROP 1 LAST BODY_TYPE PLUMBING
J 0
(-1745 1382);
DISPLAY 0.340426 (-1745 1382);
PAINT GREEN (-1745 1382);
DISPLAY INVISIBLE (-1745 1382);
FORCEPROP 2 LAST CDS_LIB mstr_symbols
J 0
(-1700 1425);
PAINT ORANGE (-1700 1425);
DISPLAY INVISIBLE (-1700 1425);
FORCEPROP 1 LAST SIZE 1B
J 0
(-1655 1447);
DISPLAY 0.340426 (-1655 1447);
PAINT GREEN (-1655 1447);
DISPLAY INVISIBLE (-1655 1447);
FORCEPROP 1 LAST VOLTAGE 3.3V
J 0
(-1745 1382);
DISPLAY 0.340426 (-1745 1382);
PAINT SKYBLUE (-1745 1382);
DISPLAY INVISIBLE (-1745 1382);
FORCEADD RES..1
(-3550 3775);
FORCEPROP 1 LAST TOLERANCE 5%
J 0
(-3725 3775);
DISPLAY 0.617021 (-3725 3775);
PAINT SKYBLUE (-3725 3775);
FORCEPROP 1 LAST LOCATION R9G9
J 0
(-3650 3775);
DISPLAY 0.617021 (-3650 3775);
PAINT AQUA (-3650 3775);
FORCEPROP 1 LAST PART_NUMBER G21497-005
J 0
(-3500 3775);
DISPLAY 0.617021 (-3500 3775);
PAINT BLUE (-3500 3775);
FORCEPROP 1 LAST VALUE 0.0
J 2
(-3200 3775);
DISPLAY 0.617021 (-3200 3775);
PAINT SKYBLUE (-3200 3775);
FORCEPROP 2 LAST CDS_LOCATION R9G9
J 0
(-3650 3775);
DISPLAY 0.617021 (-3650 3775);
PAINT AQUA (-3650 3775);
DISPLAY INVISIBLE (-3650 3775);
FORCEPROP 1 LAST WATTAGE 1/16W
J 2
(-3650 3725);
DISPLAY 0.617021 (-3650 3725);
PAINT SKYBLUE (-3650 3725);
DISPLAY INVISIBLE (-3650 3725);
FORCEPROP 1 LASTPIN (-3650 3775) $PN 1
J 0
(-3638 3787);
DISPLAY 0.787234 (-3638 3787);
PAINT ORANGE (-3638 3787);
DISPLAY INVISIBLE (-3638 3787);
FORCEPROP 2 LAST CDS_SEC 1
J 0
(-3600 3975);
PAINT MONO (-3600 3975);
DISPLAY INVISIBLE (-3600 3975);
FORCEPROP 2 LAST $SEC 1
J 0
(-3600 3975);
PAINT MONO (-3600 3975);
DISPLAY INVISIBLE (-3600 3975);
FORCEPROP 1 LAST PATH I75
J 0
(-3600 3925);
DISPLAY 0.978723 (-3600 3925);
PAINT WHITE (-3600 3925);
DISPLAY INVISIBLE (-3600 3925);
FORCEPROP 1 LAST MATERIAL CHIP
J 0
(-3475 3725);
DISPLAY 0.617021 (-3475 3725);
PAINT SKYBLUE (-3475 3725);
DISPLAY INVISIBLE (-3475 3725);
FORCEPROP 2 LAST CDS_LIB mstr_discrete
J 0
(-3550 3775);
PAINT MONO (-3550 3775);
DISPLAY INVISIBLE (-3550 3775);
FORCEPROP 1 LASTPIN (-3450 3775) $PN 2
J 0
(-3488 3787);
DISPLAY 0.787234 (-3488 3787);
PAINT ORANGE (-3488 3787);
DISPLAY INVISIBLE (-3488 3787);
FORCEPROP 1 LAST PACK_TYPE 0402
J 0
(-3375 3725);
DISPLAY 0.617021 (-3375 3725);
PAINT SKYBLUE (-3375 3725);
DISPLAY INVISIBLE (-3375 3725);
FORCEPROP 2 LAST ROOM NIC_SPRV
J 0
(-3200 3825);
DISPLAY 1.021277 (-3200 3825);
PAINT ORANGE (-3200 3825);
DISPLAY INVISIBLE (-3200 3825);
FORCEPROP 2 LAST BOM_COST NT_GBE_BASE
J 0
(-3200 3875);
DISPLAY 1.021277 (-3200 3875);
PAINT ORANGE (-3200 3875);
DISPLAY INVISIBLE (-3200 3875);
FORCEADD RES..1
(-3550 3725);
FORCEPROP 1 LAST TOLERANCE 5%
J 0
(-3725 3725);
DISPLAY 0.617021 (-3725 3725);
PAINT SKYBLUE (-3725 3725);
FORCEPROP 1 LAST LOCATION R9G11
J 0
(-3650 3725);
DISPLAY 0.617021 (-3650 3725);
PAINT AQUA (-3650 3725);
FORCEPROP 1 LAST PART_NUMBER G21497-005
J 0
(-3500 3725);
DISPLAY 0.617021 (-3500 3725);
PAINT BLUE (-3500 3725);
FORCEPROP 1 LAST VALUE 0.0
J 2
(-3200 3725);
DISPLAY 0.617021 (-3200 3725);
PAINT SKYBLUE (-3200 3725);
FORCEPROP 1 LAST WATTAGE 1/16W
J 2
(-3650 3675);
DISPLAY 0.617021 (-3650 3675);
PAINT SKYBLUE (-3650 3675);
DISPLAY INVISIBLE (-3650 3675);
FORCEPROP 2 LAST CDS_LOCATION R9G11
J 0
(-3650 3725);
DISPLAY 0.617021 (-3650 3725);
PAINT AQUA (-3650 3725);
DISPLAY INVISIBLE (-3650 3725);
FORCEPROP 1 LASTPIN (-3650 3725) $PN 1
J 0
(-3638 3737);
DISPLAY 0.787234 (-3638 3737);
PAINT ORANGE (-3638 3737);
DISPLAY INVISIBLE (-3638 3737);
FORCEPROP 2 LAST CDS_SEC 1
J 0
(-3600 3925);
PAINT MONO (-3600 3925);
DISPLAY INVISIBLE (-3600 3925);
FORCEPROP 2 LAST $SEC 1
J 0
(-3600 3925);
PAINT MONO (-3600 3925);
DISPLAY INVISIBLE (-3600 3925);
FORCEPROP 1 LAST PATH I76
J 0
(-3600 3875);
DISPLAY 0.978723 (-3600 3875);
PAINT WHITE (-3600 3875);
DISPLAY INVISIBLE (-3600 3875);
FORCEPROP 1 LAST MATERIAL CHIP
J 0
(-3475 3675);
DISPLAY 0.617021 (-3475 3675);
PAINT SKYBLUE (-3475 3675);
DISPLAY INVISIBLE (-3475 3675);
FORCEPROP 2 LAST CDS_LIB mstr_discrete
J 0
(-3550 3725);
PAINT MONO (-3550 3725);
DISPLAY INVISIBLE (-3550 3725);
FORCEPROP 1 LASTPIN (-3450 3725) $PN 2
J 0
(-3488 3737);
DISPLAY 0.787234 (-3488 3737);
PAINT ORANGE (-3488 3737);
DISPLAY INVISIBLE (-3488 3737);
FORCEPROP 1 LAST PACK_TYPE 0402
J 0
(-3375 3675);
DISPLAY 0.617021 (-3375 3675);
PAINT SKYBLUE (-3375 3675);
DISPLAY INVISIBLE (-3375 3675);
FORCEPROP 2 LAST ROOM NIC_SPRV
J 0
(-3200 3775);
DISPLAY 1.021277 (-3200 3775);
PAINT ORANGE (-3200 3775);
DISPLAY INVISIBLE (-3200 3775);
FORCEPROP 2 LAST BOM_COST NT_GBE_BASE
J 0
(-3200 3825);
DISPLAY 1.021277 (-3200 3825);
PAINT ORANGE (-3200 3825);
DISPLAY INVISIBLE (-3200 3825);
FORCEADD RES..1
(-3550 3675);
FORCEPROP 1 LAST TOLERANCE 5%
J 0
(-3725 3675);
DISPLAY 0.617021 (-3725 3675);
PAINT SKYBLUE (-3725 3675);
FORCEPROP 1 LAST LOCATION R9G18
J 0
(-3650 3675);
DISPLAY 0.617021 (-3650 3675);
PAINT AQUA (-3650 3675);
FORCEPROP 1 LAST PART_NUMBER G21497-005
J 0
(-3500 3675);
DISPLAY 0.617021 (-3500 3675);
PAINT BLUE (-3500 3675);
FORCEPROP 1 LAST VALUE 0.0
J 2
(-3200 3675);
DISPLAY 0.617021 (-3200 3675);
PAINT SKYBLUE (-3200 3675);
FORCEPROP 2 LAST CDS_LOCATION R9G18
J 0
(-3650 3675);
DISPLAY 0.617021 (-3650 3675);
PAINT AQUA (-3650 3675);
DISPLAY INVISIBLE (-3650 3675);
FORCEPROP 1 LAST WATTAGE 1/16W
J 2
(-3650 3625);
DISPLAY 0.617021 (-3650 3625);
PAINT SKYBLUE (-3650 3625);
DISPLAY INVISIBLE (-3650 3625);
FORCEPROP 1 LASTPIN (-3650 3675) $PN 1
J 0
(-3638 3687);
DISPLAY 0.787234 (-3638 3687);
PAINT ORANGE (-3638 3687);
DISPLAY INVISIBLE (-3638 3687);
FORCEPROP 1 LAST PATH I77
J 0
(-3600 3825);
DISPLAY 0.978723 (-3600 3825);
PAINT WHITE (-3600 3825);
DISPLAY INVISIBLE (-3600 3825);
FORCEPROP 2 LAST CDS_SEC 1
J 0
(-3600 3875);
PAINT MONO (-3600 3875);
DISPLAY INVISIBLE (-3600 3875);
FORCEPROP 2 LAST $SEC 1
J 0
(-3600 3875);
PAINT MONO (-3600 3875);
DISPLAY INVISIBLE (-3600 3875);
FORCEPROP 1 LAST MATERIAL CHIP
J 0
(-3475 3625);
DISPLAY 0.617021 (-3475 3625);
PAINT SKYBLUE (-3475 3625);
DISPLAY INVISIBLE (-3475 3625);
FORCEPROP 2 LAST CDS_LIB mstr_discrete
J 0
(-3550 3675);
PAINT MONO (-3550 3675);
DISPLAY INVISIBLE (-3550 3675);
FORCEPROP 1 LASTPIN (-3450 3675) $PN 2
J 0
(-3488 3687);
DISPLAY 0.787234 (-3488 3687);
PAINT ORANGE (-3488 3687);
DISPLAY INVISIBLE (-3488 3687);
FORCEPROP 1 LAST PACK_TYPE 0402
J 0
(-3375 3625);
DISPLAY 0.617021 (-3375 3625);
PAINT SKYBLUE (-3375 3625);
DISPLAY INVISIBLE (-3375 3625);
FORCEPROP 2 LAST BOM_COST NT_GBE_BASE
J 0
(-3200 3775);
DISPLAY 1.021277 (-3200 3775);
PAINT ORANGE (-3200 3775);
DISPLAY INVISIBLE (-3200 3775);
FORCEPROP 2 LAST ROOM NIC_SPRV
J 0
(-3200 3725);
DISPLAY 1.021277 (-3200 3725);
PAINT ORANGE (-3200 3725);
DISPLAY INVISIBLE (-3200 3725);
FORCEADD RES..1
(-3550 3625);
FORCEPROP 1 LAST TOLERANCE 5%
J 0
(-3725 3625);
DISPLAY 0.617021 (-3725 3625);
PAINT SKYBLUE (-3725 3625);
FORCEPROP 1 LAST LOCATION R9G17
J 0
(-3650 3625);
DISPLAY 0.617021 (-3650 3625);
PAINT AQUA (-3650 3625);
FORCEPROP 1 LAST PART_NUMBER G21497-005
J 0
(-3500 3625);
DISPLAY 0.617021 (-3500 3625);
PAINT BLUE (-3500 3625);
FORCEPROP 1 LAST VALUE 0.0
J 2
(-3200 3625);
DISPLAY 0.617021 (-3200 3625);
PAINT SKYBLUE (-3200 3625);
FORCEPROP 1 LAST WATTAGE 1/16W
J 2
(-3650 3575);
DISPLAY 0.617021 (-3650 3575);
PAINT SKYBLUE (-3650 3575);
DISPLAY INVISIBLE (-3650 3575);
FORCEPROP 2 LAST CDS_LOCATION R9G17
J 0
(-3650 3625);
DISPLAY 0.617021 (-3650 3625);
PAINT AQUA (-3650 3625);
DISPLAY INVISIBLE (-3650 3625);
FORCEPROP 1 LASTPIN (-3650 3625) $PN 1
J 0
(-3638 3637);
DISPLAY 0.787234 (-3638 3637);
PAINT ORANGE (-3638 3637);
DISPLAY INVISIBLE (-3638 3637);
FORCEPROP 1 LAST PATH I78
J 0
(-3600 3775);
DISPLAY 0.978723 (-3600 3775);
PAINT WHITE (-3600 3775);
DISPLAY INVISIBLE (-3600 3775);
FORCEPROP 2 LAST CDS_SEC 1
J 0
(-3600 3825);
PAINT MONO (-3600 3825);
DISPLAY INVISIBLE (-3600 3825);
FORCEPROP 2 LAST $SEC 1
J 0
(-3600 3825);
PAINT MONO (-3600 3825);
DISPLAY INVISIBLE (-3600 3825);
FORCEPROP 1 LAST PACK_TYPE 0402
J 0
(-3375 3575);
DISPLAY 0.617021 (-3375 3575);
PAINT SKYBLUE (-3375 3575);
DISPLAY INVISIBLE (-3375 3575);
FORCEPROP 1 LAST MATERIAL CHIP
J 0
(-3475 3575);
DISPLAY 0.617021 (-3475 3575);
PAINT SKYBLUE (-3475 3575);
DISPLAY INVISIBLE (-3475 3575);
FORCEPROP 2 LAST CDS_LIB mstr_discrete
J 0
(-3550 3625);
PAINT MONO (-3550 3625);
DISPLAY INVISIBLE (-3550 3625);
FORCEPROP 1 LASTPIN (-3450 3625) $PN 2
J 0
(-3488 3637);
DISPLAY 0.787234 (-3488 3637);
PAINT ORANGE (-3488 3637);
DISPLAY INVISIBLE (-3488 3637);
FORCEPROP 2 LAST BOM_COST NT_GBE_BASE
J 0
(-3200 3725);
DISPLAY 1.021277 (-3200 3725);
PAINT ORANGE (-3200 3725);
DISPLAY INVISIBLE (-3200 3725);
FORCEPROP 2 LAST ROOM NIC_SPRV
J 0
(-3200 3675);
DISPLAY 1.021277 (-3200 3675);
PAINT ORANGE (-3200 3675);
DISPLAY INVISIBLE (-3200 3675);
FORCEADD RES..1
(-3550 3575);
FORCEPROP 1 LAST TOLERANCE 5%
J 0
(-3725 3575);
DISPLAY 0.617021 (-3725 3575);
PAINT SKYBLUE (-3725 3575);
FORCEPROP 1 LAST LOCATION R9G19
J 0
(-3650 3575);
DISPLAY 0.617021 (-3650 3575);
PAINT AQUA (-3650 3575);
FORCEPROP 1 LAST PART_NUMBER G21497-005
J 0
(-3500 3575);
DISPLAY 0.617021 (-3500 3575);
PAINT BLUE (-3500 3575);
FORCEPROP 1 LAST VALUE 0.0
J 2
(-3200 3575);
DISPLAY 0.617021 (-3200 3575);
PAINT SKYBLUE (-3200 3575);
FORCEPROP 1 LAST WATTAGE 1/16W
J 2
(-3650 3525);
DISPLAY 0.617021 (-3650 3525);
PAINT SKYBLUE (-3650 3525);
DISPLAY INVISIBLE (-3650 3525);
FORCEPROP 2 LAST CDS_LOCATION R9G19
J 0
(-3650 3575);
DISPLAY 0.617021 (-3650 3575);
PAINT AQUA (-3650 3575);
DISPLAY INVISIBLE (-3650 3575);
FORCEPROP 1 LASTPIN (-3650 3575) $PN 1
J 0
(-3638 3587);
DISPLAY 0.787234 (-3638 3587);
PAINT ORANGE (-3638 3587);
DISPLAY INVISIBLE (-3638 3587);
FORCEPROP 1 LAST PATH I79
J 0
(-3600 3725);
DISPLAY 0.978723 (-3600 3725);
PAINT WHITE (-3600 3725);
DISPLAY INVISIBLE (-3600 3725);
FORCEPROP 2 LAST $SEC 1
J 0
(-3600 3775);
PAINT MONO (-3600 3775);
DISPLAY INVISIBLE (-3600 3775);
FORCEPROP 2 LAST CDS_SEC 1
J 0
(-3600 3775);
PAINT MONO (-3600 3775);
DISPLAY INVISIBLE (-3600 3775);
FORCEPROP 1 LAST MATERIAL CHIP
J 0
(-3475 3525);
DISPLAY 0.617021 (-3475 3525);
PAINT SKYBLUE (-3475 3525);
DISPLAY INVISIBLE (-3475 3525);
FORCEPROP 1 LAST PACK_TYPE 0402
J 0
(-3375 3525);
DISPLAY 0.617021 (-3375 3525);
PAINT SKYBLUE (-3375 3525);
DISPLAY INVISIBLE (-3375 3525);
FORCEPROP 2 LAST CDS_LIB mstr_discrete
J 0
(-3550 3575);
PAINT MONO (-3550 3575);
DISPLAY INVISIBLE (-3550 3575);
FORCEPROP 1 LASTPIN (-3450 3575) $PN 2
J 0
(-3488 3587);
DISPLAY 0.787234 (-3488 3587);
PAINT ORANGE (-3488 3587);
DISPLAY INVISIBLE (-3488 3587);
FORCEPROP 2 LAST BOM_COST NT_GBE_BASE
J 0
(-3200 3675);
DISPLAY 1.021277 (-3200 3675);
PAINT ORANGE (-3200 3675);
DISPLAY INVISIBLE (-3200 3675);
FORCEPROP 2 LAST ROOM NIC_SPRV
J 0
(-3200 3625);
DISPLAY 1.021277 (-3200 3625);
PAINT ORANGE (-3200 3625);
DISPLAY INVISIBLE (-3200 3625);
FORCEADD RES..1
(-3550 3525);
FORCEPROP 1 LAST TOLERANCE 5%
J 0
(-3725 3525);
DISPLAY 0.617021 (-3725 3525);
PAINT SKYBLUE (-3725 3525);
FORCEPROP 1 LAST LOCATION R9G20
J 0
(-3650 3525);
DISPLAY 0.617021 (-3650 3525);
PAINT AQUA (-3650 3525);
FORCEPROP 1 LAST PART_NUMBER G21497-005
J 0
(-3500 3525);
DISPLAY 0.617021 (-3500 3525);
PAINT BLUE (-3500 3525);
FORCEPROP 1 LAST VALUE 0.0
J 2
(-3200 3525);
DISPLAY 0.617021 (-3200 3525);
PAINT SKYBLUE (-3200 3525);
FORCEPROP 2 LAST CDS_LOCATION R9G20
J 0
(-3650 3525);
DISPLAY 0.617021 (-3650 3525);
PAINT AQUA (-3650 3525);
DISPLAY INVISIBLE (-3650 3525);
FORCEPROP 1 LAST WATTAGE 1/16W
J 2
(-3650 3475);
DISPLAY 0.617021 (-3650 3475);
PAINT SKYBLUE (-3650 3475);
DISPLAY INVISIBLE (-3650 3475);
FORCEPROP 1 LASTPIN (-3650 3525) $PN 1
J 0
(-3638 3537);
DISPLAY 0.787234 (-3638 3537);
PAINT ORANGE (-3638 3537);
DISPLAY INVISIBLE (-3638 3537);
FORCEPROP 1 LAST PATH I80
J 0
(-3600 3675);
DISPLAY 0.978723 (-3600 3675);
PAINT WHITE (-3600 3675);
DISPLAY INVISIBLE (-3600 3675);
FORCEPROP 2 LAST $SEC 1
J 0
(-3600 3725);
PAINT MONO (-3600 3725);
DISPLAY INVISIBLE (-3600 3725);
FORCEPROP 2 LAST CDS_SEC 1
J 0
(-3600 3725);
PAINT MONO (-3600 3725);
DISPLAY INVISIBLE (-3600 3725);
FORCEPROP 2 LAST CDS_LIB mstr_discrete
J 0
(-3550 3525);
PAINT MONO (-3550 3525);
DISPLAY INVISIBLE (-3550 3525);
FORCEPROP 1 LAST MATERIAL CHIP
J 0
(-3475 3475);
DISPLAY 0.617021 (-3475 3475);
PAINT SKYBLUE (-3475 3475);
DISPLAY INVISIBLE (-3475 3475);
FORCEPROP 1 LASTPIN (-3450 3525) $PN 2
J 0
(-3488 3537);
DISPLAY 0.787234 (-3488 3537);
PAINT ORANGE (-3488 3537);
DISPLAY INVISIBLE (-3488 3537);
FORCEPROP 1 LAST PACK_TYPE 0402
J 0
(-3375 3475);
DISPLAY 0.617021 (-3375 3475);
PAINT SKYBLUE (-3375 3475);
DISPLAY INVISIBLE (-3375 3475);
FORCEPROP 2 LAST ROOM NIC_SPRV
J 0
(-3200 3575);
DISPLAY 1.021277 (-3200 3575);
PAINT ORANGE (-3200 3575);
DISPLAY INVISIBLE (-3200 3575);
FORCEPROP 2 LAST BOM_COST NT_GBE_BASE
J 0
(-3200 3625);
DISPLAY 1.021277 (-3200 3625);
PAINT ORANGE (-3200 3625);
DISPLAY INVISIBLE (-3200 3625);
FORCEADD RES..1
(-3550 3475);
FORCEPROP 1 LAST TOLERANCE 5%
J 0
(-3725 3475);
DISPLAY 0.617021 (-3725 3475);
PAINT SKYBLUE (-3725 3475);
FORCEPROP 1 LAST LOCATION R9G24
J 0
(-3650 3475);
DISPLAY 0.617021 (-3650 3475);
PAINT AQUA (-3650 3475);
FORCEPROP 1 LAST PART_NUMBER G21497-005
J 0
(-3500 3475);
DISPLAY 0.617021 (-3500 3475);
PAINT BLUE (-3500 3475);
FORCEPROP 1 LAST VALUE 0.0
J 2
(-3200 3475);
DISPLAY 0.617021 (-3200 3475);
PAINT SKYBLUE (-3200 3475);
FORCEPROP 1 LAST WATTAGE 1/16W
J 2
(-3650 3425);
DISPLAY 0.617021 (-3650 3425);
PAINT SKYBLUE (-3650 3425);
DISPLAY INVISIBLE (-3650 3425);
FORCEPROP 2 LAST CDS_LOCATION R9G24
J 0
(-3650 3475);
DISPLAY 0.617021 (-3650 3475);
PAINT AQUA (-3650 3475);
DISPLAY INVISIBLE (-3650 3475);
FORCEPROP 1 LASTPIN (-3650 3475) $PN 1
J 0
(-3638 3487);
DISPLAY 0.787234 (-3638 3487);
PAINT ORANGE (-3638 3487);
DISPLAY INVISIBLE (-3638 3487);
FORCEPROP 1 LAST PATH I81
J 0
(-3600 3625);
DISPLAY 0.978723 (-3600 3625);
PAINT WHITE (-3600 3625);
DISPLAY INVISIBLE (-3600 3625);
FORCEPROP 2 LAST $SEC 1
J 0
(-3600 3675);
PAINT MONO (-3600 3675);
DISPLAY INVISIBLE (-3600 3675);
FORCEPROP 2 LAST CDS_SEC 1
J 0
(-3600 3675);
PAINT MONO (-3600 3675);
DISPLAY INVISIBLE (-3600 3675);
FORCEPROP 1 LAST MATERIAL CHIP
J 0
(-3475 3425);
DISPLAY 0.617021 (-3475 3425);
PAINT SKYBLUE (-3475 3425);
DISPLAY INVISIBLE (-3475 3425);
FORCEPROP 2 LAST CDS_LIB mstr_discrete
J 0
(-3550 3475);
PAINT MONO (-3550 3475);
DISPLAY INVISIBLE (-3550 3475);
FORCEPROP 1 LASTPIN (-3450 3475) $PN 2
J 0
(-3488 3487);
DISPLAY 0.787234 (-3488 3487);
PAINT ORANGE (-3488 3487);
DISPLAY INVISIBLE (-3488 3487);
FORCEPROP 1 LAST PACK_TYPE 0402
J 0
(-3375 3425);
DISPLAY 0.617021 (-3375 3425);
PAINT SKYBLUE (-3375 3425);
DISPLAY INVISIBLE (-3375 3425);
FORCEPROP 2 LAST ROOM NIC_SPRV
J 0
(-3200 3525);
DISPLAY 1.021277 (-3200 3525);
PAINT ORANGE (-3200 3525);
DISPLAY INVISIBLE (-3200 3525);
FORCEPROP 2 LAST BOM_COST NT_GBE_BASE
J 0
(-3200 3575);
DISPLAY 1.021277 (-3200 3575);
PAINT ORANGE (-3200 3575);
DISPLAY INVISIBLE (-3200 3575);
FORCEADD RES..1
(-3550 3425);
FORCEPROP 1 LAST TOLERANCE 5%
J 0
(-3725 3425);
DISPLAY 0.617021 (-3725 3425);
PAINT SKYBLUE (-3725 3425);
FORCEPROP 1 LAST LOCATION R9G22
J 0
(-3650 3425);
DISPLAY 0.617021 (-3650 3425);
PAINT AQUA (-3650 3425);
FORCEPROP 1 LAST PART_NUMBER G21497-005
J 0
(-3500 3425);
DISPLAY 0.617021 (-3500 3425);
PAINT BLUE (-3500 3425);
FORCEPROP 1 LAST VALUE 0.0
J 2
(-3200 3425);
DISPLAY 0.617021 (-3200 3425);
PAINT SKYBLUE (-3200 3425);
FORCEPROP 2 LAST CDS_LOCATION R9G22
J 0
(-3650 3425);
DISPLAY 0.617021 (-3650 3425);
PAINT AQUA (-3650 3425);
DISPLAY INVISIBLE (-3650 3425);
FORCEPROP 1 LAST WATTAGE 1/16W
J 2
(-3650 3375);
DISPLAY 0.617021 (-3650 3375);
PAINT SKYBLUE (-3650 3375);
DISPLAY INVISIBLE (-3650 3375);
FORCEPROP 1 LASTPIN (-3650 3425) $PN 1
J 0
(-3638 3437);
DISPLAY 0.787234 (-3638 3437);
PAINT ORANGE (-3638 3437);
DISPLAY INVISIBLE (-3638 3437);
FORCEPROP 1 LAST PATH I82
J 0
(-3600 3575);
DISPLAY 0.978723 (-3600 3575);
PAINT WHITE (-3600 3575);
DISPLAY INVISIBLE (-3600 3575);
FORCEPROP 2 LAST CDS_SEC 1
J 0
(-3600 3625);
PAINT MONO (-3600 3625);
DISPLAY INVISIBLE (-3600 3625);
FORCEPROP 2 LAST $SEC 1
J 0
(-3600 3625);
PAINT MONO (-3600 3625);
DISPLAY INVISIBLE (-3600 3625);
FORCEPROP 1 LAST MATERIAL CHIP
J 0
(-3475 3375);
DISPLAY 0.617021 (-3475 3375);
PAINT SKYBLUE (-3475 3375);
DISPLAY INVISIBLE (-3475 3375);
FORCEPROP 2 LAST CDS_LIB mstr_discrete
J 0
(-3550 3425);
PAINT MONO (-3550 3425);
DISPLAY INVISIBLE (-3550 3425);
FORCEPROP 1 LASTPIN (-3450 3425) $PN 2
J 0
(-3488 3437);
DISPLAY 0.787234 (-3488 3437);
PAINT ORANGE (-3488 3437);
DISPLAY INVISIBLE (-3488 3437);
FORCEPROP 1 LAST PACK_TYPE 0402
J 0
(-3375 3375);
DISPLAY 0.617021 (-3375 3375);
PAINT SKYBLUE (-3375 3375);
DISPLAY INVISIBLE (-3375 3375);
FORCEPROP 2 LAST BOM_COST NT_GBE_BASE
J 0
(-3200 3525);
DISPLAY 1.021277 (-3200 3525);
PAINT ORANGE (-3200 3525);
DISPLAY INVISIBLE (-3200 3525);
FORCEPROP 2 LAST ROOM NIC_SPRV
J 0
(-3200 3475);
DISPLAY 1.021277 (-3200 3475);
PAINT ORANGE (-3200 3475);
DISPLAY INVISIBLE (-3200 3475);
FORCEADD OFFPAGE..3
(-2625 3775);
FORCEPROP 2 LAST $XR0 141 
J 0
(-2411 3775);
DISPLAY 0.638298 (-2411 3775);
PAINT MONO (-2411 3775);
FORCEPROP 1 LAST COMMENT_BODY TRUE
J 0
(-2675 3675);
DISPLAY 0.872340 (-2675 3675);
PAINT GREEN (-2675 3675);
DISPLAY INVISIBLE (-2675 3675);
FORCEPROP 2 LAST CDS_LIB mstr_standard
J 0
(-2625 3775);
PAINT MONO (-2625 3775);
DISPLAY INVISIBLE (-2625 3775);
FORCEPROP 2 LAST PATH I83
J 0
(-2575 3850);
DISPLAY 1.021277 (-2575 3850);
PAINT ORANGE (-2575 3850);
DISPLAY INVISIBLE (-2575 3850);
FORCEPROP 1 LAST OFFPAGE TRUE
J 0
(-2300 3650);
DISPLAY 0.872340 (-2300 3650);
PAINT GREEN (-2300 3650);
DISPLAY INVISIBLE (-2300 3650);
FORCEADD OFFPAGE..3
(-2625 3725);
FORCEPROP 2 LAST $XR0 141 
J 0
(-2411 3725);
DISPLAY 0.638298 (-2411 3725);
PAINT MONO (-2411 3725);
FORCEPROP 1 LAST COMMENT_BODY TRUE
J 0
(-2675 3625);
DISPLAY 0.872340 (-2675 3625);
PAINT GREEN (-2675 3625);
DISPLAY INVISIBLE (-2675 3625);
FORCEPROP 2 LAST CDS_LIB mstr_standard
J 0
(-2625 3725);
PAINT MONO (-2625 3725);
DISPLAY INVISIBLE (-2625 3725);
FORCEPROP 2 LAST PATH I84
J 0
(-2425 3800);
DISPLAY 1.021277 (-2425 3800);
PAINT ORANGE (-2425 3800);
DISPLAY INVISIBLE (-2425 3800);
FORCEPROP 1 LAST OFFPAGE TRUE
J 0
(-2300 3600);
DISPLAY 0.872340 (-2300 3600);
PAINT GREEN (-2300 3600);
DISPLAY INVISIBLE (-2300 3600);
FORCEADD OFFPAGE..3
(-2625 3675);
FORCEPROP 2 LAST $XR0 141 
J 0
(-2411 3675);
DISPLAY 0.638298 (-2411 3675);
PAINT MONO (-2411 3675);
FORCEPROP 1 LAST COMMENT_BODY TRUE
J 0
(-2675 3575);
DISPLAY 0.872340 (-2675 3575);
PAINT GREEN (-2675 3575);
DISPLAY INVISIBLE (-2675 3575);
FORCEPROP 2 LAST CDS_LIB mstr_standard
J 0
(-2625 3675);
PAINT MONO (-2625 3675);
DISPLAY INVISIBLE (-2625 3675);
FORCEPROP 1 LAST OFFPAGE TRUE
J 0
(-2300 3550);
DISPLAY 0.872340 (-2300 3550);
PAINT GREEN (-2300 3550);
DISPLAY INVISIBLE (-2300 3550);
FORCEPROP 2 LAST PATH I85
J 0
(-2425 3750);
DISPLAY 1.021277 (-2425 3750);
PAINT ORANGE (-2425 3750);
DISPLAY INVISIBLE (-2425 3750);
FORCEADD OFFPAGE..3
(-2625 3625);
FORCEPROP 2 LAST $XR0 141 
J 0
(-2411 3625);
DISPLAY 0.638298 (-2411 3625);
PAINT MONO (-2411 3625);
FORCEPROP 1 LAST COMMENT_BODY TRUE
J 0
(-2675 3525);
DISPLAY 0.872340 (-2675 3525);
PAINT GREEN (-2675 3525);
DISPLAY INVISIBLE (-2675 3525);
FORCEPROP 2 LAST CDS_LIB mstr_standard
J 0
(-2625 3625);
PAINT MONO (-2625 3625);
DISPLAY INVISIBLE (-2625 3625);
FORCEPROP 1 LAST OFFPAGE TRUE
J 0
(-2300 3500);
DISPLAY 0.872340 (-2300 3500);
PAINT GREEN (-2300 3500);
DISPLAY INVISIBLE (-2300 3500);
FORCEPROP 2 LAST PATH I86
J 0
(-2425 3700);
DISPLAY 1.021277 (-2425 3700);
PAINT ORANGE (-2425 3700);
DISPLAY INVISIBLE (-2425 3700);
FORCEADD OFFPAGE..3
(-2625 3575);
FORCEPROP 2 LAST $XR0 141 
J 0
(-2411 3575);
DISPLAY 0.638298 (-2411 3575);
PAINT MONO (-2411 3575);
FORCEPROP 1 LAST COMMENT_BODY TRUE
J 0
(-2675 3475);
DISPLAY 0.872340 (-2675 3475);
PAINT GREEN (-2675 3475);
DISPLAY INVISIBLE (-2675 3475);
FORCEPROP 2 LAST CDS_LIB mstr_standard
J 0
(-2625 3575);
PAINT MONO (-2625 3575);
DISPLAY INVISIBLE (-2625 3575);
FORCEPROP 1 LAST OFFPAGE TRUE
J 0
(-2300 3450);
DISPLAY 0.872340 (-2300 3450);
PAINT GREEN (-2300 3450);
DISPLAY INVISIBLE (-2300 3450);
FORCEPROP 2 LAST PATH I87
J 0
(-2425 3650);
DISPLAY 1.021277 (-2425 3650);
PAINT ORANGE (-2425 3650);
DISPLAY INVISIBLE (-2425 3650);
FORCEADD OFFPAGE..3
(-2625 3525);
FORCEPROP 2 LAST $XR0 141 
J 0
(-2411 3525);
DISPLAY 0.638298 (-2411 3525);
PAINT MONO (-2411 3525);
FORCEPROP 1 LAST COMMENT_BODY TRUE
J 0
(-2675 3425);
DISPLAY 0.872340 (-2675 3425);
PAINT GREEN (-2675 3425);
DISPLAY INVISIBLE (-2675 3425);
FORCEPROP 2 LAST CDS_LIB mstr_standard
J 0
(-2625 3525);
PAINT MONO (-2625 3525);
DISPLAY INVISIBLE (-2625 3525);
FORCEPROP 1 LAST OFFPAGE TRUE
J 0
(-2300 3400);
DISPLAY 0.872340 (-2300 3400);
PAINT GREEN (-2300 3400);
DISPLAY INVISIBLE (-2300 3400);
FORCEPROP 2 LAST PATH I88
J 0
(-2425 3600);
DISPLAY 1.021277 (-2425 3600);
PAINT ORANGE (-2425 3600);
DISPLAY INVISIBLE (-2425 3600);
FORCEADD OFFPAGE..3
(-2625 3475);
FORCEPROP 2 LAST $XR0 141 
J 0
(-2411 3475);
DISPLAY 0.638298 (-2411 3475);
PAINT MONO (-2411 3475);
FORCEPROP 1 LAST COMMENT_BODY TRUE
J 0
(-2675 3375);
DISPLAY 0.872340 (-2675 3375);
PAINT GREEN (-2675 3375);
DISPLAY INVISIBLE (-2675 3375);
FORCEPROP 2 LAST CDS_LIB mstr_standard
J 0
(-2625 3475);
PAINT MONO (-2625 3475);
DISPLAY INVISIBLE (-2625 3475);
FORCEPROP 1 LAST OFFPAGE TRUE
J 0
(-2300 3350);
DISPLAY 0.872340 (-2300 3350);
PAINT GREEN (-2300 3350);
DISPLAY INVISIBLE (-2300 3350);
FORCEPROP 2 LAST PATH I89
J 0
(-2425 3550);
DISPLAY 1.021277 (-2425 3550);
PAINT ORANGE (-2425 3550);
DISPLAY INVISIBLE (-2425 3550);
FORCEADD OFFPAGE..3
(-2625 3425);
FORCEPROP 2 LAST $XR0 141 
J 0
(-2411 3425);
DISPLAY 0.638298 (-2411 3425);
PAINT MONO (-2411 3425);
FORCEPROP 1 LAST COMMENT_BODY TRUE
J 0
(-2675 3325);
DISPLAY 0.872340 (-2675 3325);
PAINT GREEN (-2675 3325);
DISPLAY INVISIBLE (-2675 3325);
FORCEPROP 2 LAST CDS_LIB mstr_standard
J 0
(-2625 3425);
PAINT MONO (-2625 3425);
DISPLAY INVISIBLE (-2625 3425);
FORCEPROP 2 LAST PATH I90
J 0
(-2425 3500);
DISPLAY 1.021277 (-2425 3500);
PAINT ORANGE (-2425 3500);
DISPLAY INVISIBLE (-2425 3500);
FORCEPROP 1 LAST OFFPAGE TRUE
J 0
(-2300 3300);
DISPLAY 0.872340 (-2300 3300);
PAINT GREEN (-2300 3300);
DISPLAY INVISIBLE (-2300 3300);
FORCEADD OFFPAGE..6
(-4375 3425);
FORCEPROP 2 LAST $XR0 139 
J 0
(-4685 3425);
DISPLAY 0.638298 (-4685 3425);
PAINT MONO (-4685 3425);
FORCEPROP 2 LAST CDS_LIB mstr_standard
J 0
(-4375 3425);
PAINT MONO (-4375 3425);
DISPLAY INVISIBLE (-4375 3425);
FORCEPROP 1 LAST COMMENT_BODY TRUE
J 0
(-4275 3350);
DISPLAY 0.872340 (-4275 3350);
PAINT GREEN (-4275 3350);
DISPLAY INVISIBLE (-4275 3350);
FORCEPROP 2 LAST PATH I91
J 0
(-4325 3500);
DISPLAY 1.021277 (-4325 3500);
PAINT ORANGE (-4325 3500);
DISPLAY INVISIBLE (-4325 3500);
FORCEPROP 1 LAST OFFPAGE TRUE
J 0
(-4050 3300);
DISPLAY 0.872340 (-4050 3300);
PAINT GREEN (-4050 3300);
DISPLAY INVISIBLE (-4050 3300);
FORCEADD OFFPAGE..6
(-4375 3475);
FORCEPROP 2 LAST $XR0 139 
J 0
(-4685 3475);
DISPLAY 0.638298 (-4685 3475);
PAINT MONO (-4685 3475);
FORCEPROP 2 LAST CDS_LIB mstr_standard
J 0
(-4375 3475);
PAINT MONO (-4375 3475);
DISPLAY INVISIBLE (-4375 3475);
FORCEPROP 1 LAST COMMENT_BODY TRUE
J 0
(-4275 3400);
DISPLAY 0.872340 (-4275 3400);
PAINT GREEN (-4275 3400);
DISPLAY INVISIBLE (-4275 3400);
FORCEPROP 2 LAST PATH I92
J 0
(-4325 3550);
DISPLAY 1.021277 (-4325 3550);
PAINT ORANGE (-4325 3550);
DISPLAY INVISIBLE (-4325 3550);
FORCEPROP 1 LAST OFFPAGE TRUE
J 0
(-4050 3350);
DISPLAY 0.872340 (-4050 3350);
PAINT GREEN (-4050 3350);
DISPLAY INVISIBLE (-4050 3350);
FORCEADD OFFPAGE..6
(-4375 3525);
FORCEPROP 2 LAST $XR0 139 
J 0
(-4685 3525);
DISPLAY 0.638298 (-4685 3525);
PAINT MONO (-4685 3525);
FORCEPROP 2 LAST CDS_LIB mstr_standard
J 0
(-4375 3525);
PAINT MONO (-4375 3525);
DISPLAY INVISIBLE (-4375 3525);
FORCEPROP 1 LAST COMMENT_BODY TRUE
J 0
(-4275 3450);
DISPLAY 0.872340 (-4275 3450);
PAINT GREEN (-4275 3450);
DISPLAY INVISIBLE (-4275 3450);
FORCEPROP 2 LAST PATH I93
J 0
(-4325 3600);
DISPLAY 1.021277 (-4325 3600);
PAINT ORANGE (-4325 3600);
DISPLAY INVISIBLE (-4325 3600);
FORCEPROP 1 LAST OFFPAGE TRUE
J 0
(-4050 3400);
DISPLAY 0.872340 (-4050 3400);
PAINT GREEN (-4050 3400);
DISPLAY INVISIBLE (-4050 3400);
FORCEADD OFFPAGE..6
(-4375 3575);
FORCEPROP 2 LAST $XR0 139 
J 0
(-4685 3575);
DISPLAY 0.638298 (-4685 3575);
PAINT MONO (-4685 3575);
FORCEPROP 1 LAST COMMENT_BODY TRUE
J 0
(-4275 3500);
DISPLAY 0.872340 (-4275 3500);
PAINT GREEN (-4275 3500);
DISPLAY INVISIBLE (-4275 3500);
FORCEPROP 2 LAST CDS_LIB mstr_standard
J 0
(-4375 3575);
PAINT MONO (-4375 3575);
DISPLAY INVISIBLE (-4375 3575);
FORCEPROP 2 LAST PATH I94
J 0
(-4325 3650);
DISPLAY 1.021277 (-4325 3650);
PAINT ORANGE (-4325 3650);
DISPLAY INVISIBLE (-4325 3650);
FORCEPROP 1 LAST OFFPAGE TRUE
J 0
(-4050 3450);
DISPLAY 0.872340 (-4050 3450);
PAINT GREEN (-4050 3450);
DISPLAY INVISIBLE (-4050 3450);
FORCEADD OFFPAGE..6
(-4775 4025);
FORCEPROP 2 LAST $XR0 139 
J 0
(-5085 4025);
DISPLAY 0.638298 (-5085 4025);
PAINT MONO (-5085 4025);
FORCEPROP 2 LAST CDS_LIB mstr_standard
J 0
(-4775 4025);
PAINT MONO (-4775 4025);
DISPLAY INVISIBLE (-4775 4025);
FORCEPROP 1 LAST COMMENT_BODY TRUE
J 0
(-4675 3950);
DISPLAY 0.872340 (-4675 3950);
PAINT GREEN (-4675 3950);
DISPLAY INVISIBLE (-4675 3950);
FORCEPROP 1 LAST OFFPAGE TRUE
J 0
(-4450 3900);
DISPLAY 0.872340 (-4450 3900);
PAINT GREEN (-4450 3900);
DISPLAY INVISIBLE (-4450 3900);
FORCEPROP 2 LAST PATH I95
J 0
(-4725 4100);
DISPLAY 1.021277 (-4725 4100);
PAINT ORANGE (-4725 4100);
DISPLAY INVISIBLE (-4725 4100);
FORCEADD OFFPAGE..6
(-4775 4075);
FORCEPROP 2 LAST $XR0 139 
J 0
(-5085 4075);
DISPLAY 0.638298 (-5085 4075);
PAINT MONO (-5085 4075);
FORCEPROP 1 LAST COMMENT_BODY TRUE
J 0
(-4675 4000);
DISPLAY 0.872340 (-4675 4000);
PAINT GREEN (-4675 4000);
DISPLAY INVISIBLE (-4675 4000);
FORCEPROP 1 LAST OFFPAGE TRUE
J 0
(-4450 3950);
DISPLAY 0.872340 (-4450 3950);
PAINT GREEN (-4450 3950);
DISPLAY INVISIBLE (-4450 3950);
FORCEPROP 2 LAST CDS_LIB mstr_standard
J 0
(-4775 4075);
PAINT MONO (-4775 4075);
DISPLAY INVISIBLE (-4775 4075);
FORCEPROP 2 LAST PATH I96
J 0
(-4725 4150);
DISPLAY 1.021277 (-4725 4150);
PAINT ORANGE (-4725 4150);
DISPLAY INVISIBLE (-4725 4150);
FORCEADD OFFPAGE..6
(-4775 4125);
FORCEPROP 2 LAST $XR0 139 
J 0
(-5085 4125);
DISPLAY 0.638298 (-5085 4125);
PAINT MONO (-5085 4125);
FORCEPROP 1 LAST COMMENT_BODY TRUE
J 0
(-4675 4050);
DISPLAY 0.872340 (-4675 4050);
PAINT GREEN (-4675 4050);
DISPLAY INVISIBLE (-4675 4050);
FORCEPROP 1 LAST OFFPAGE TRUE
J 0
(-4450 4000);
DISPLAY 0.872340 (-4450 4000);
PAINT GREEN (-4450 4000);
DISPLAY INVISIBLE (-4450 4000);
FORCEPROP 2 LAST CDS_LIB mstr_standard
J 0
(-4775 4125);
PAINT MONO (-4775 4125);
DISPLAY INVISIBLE (-4775 4125);
FORCEPROP 2 LAST PATH I97
J 0
(-4725 4200);
DISPLAY 1.021277 (-4725 4200);
PAINT ORANGE (-4725 4200);
DISPLAY INVISIBLE (-4725 4200);
FORCEADD OFFPAGE..6
(-4775 4175);
FORCEPROP 2 LAST $XR0 139 
J 0
(-5085 4175);
DISPLAY 0.638298 (-5085 4175);
PAINT MONO (-5085 4175);
FORCEPROP 1 LAST OFFPAGE TRUE
J 0
(-4450 4050);
DISPLAY 0.872340 (-4450 4050);
PAINT GREEN (-4450 4050);
DISPLAY INVISIBLE (-4450 4050);
FORCEPROP 2 LAST CDS_LIB mstr_standard
J 0
(-4775 4175);
PAINT MONO (-4775 4175);
DISPLAY INVISIBLE (-4775 4175);
FORCEPROP 1 LAST COMMENT_BODY TRUE
J 0
(-4675 4100);
DISPLAY 0.872340 (-4675 4100);
PAINT GREEN (-4675 4100);
DISPLAY INVISIBLE (-4675 4100);
FORCEPROP 2 LAST PATH I98
J 0
(-4725 4250);
DISPLAY 1.021277 (-4725 4250);
PAINT ORANGE (-4725 4250);
DISPLAY INVISIBLE (-4725 4250);
FORCEADD CAP..2
(-2875 4425);
FORCEPROP 1 LAST LOCATION C9G9
J 1
(-3325 4425);
DISPLAY 0.617021 (-3325 4425);
PAINT AQUA (-3325 4425);
FORCEPROP 1 LAST PART_NUMBER A36096-066
J 1
(-3175 4425);
DISPLAY 0.617021 (-3175 4425);
PAINT BLUE (-3175 4425);
FORCEPROP 1 LAST VALUE 4700PF
J 2
(-2900 4425);
DISPLAY 0.617021 (-2900 4425);
PAINT SKYBLUE (-2900 4425);
FORCEPROP 1 LAST TOLERANCE 10%
J 2
(-2625 4425);
DISPLAY 0.617021 (-2625 4425);
PAINT SKYBLUE (-2625 4425);
FORCEPROP 1 LAST MATERIAL EMPTY
J 0
(-2800 4425);
DISPLAY 0.617021 (-2800 4425);
PAINT RED (-2800 4425);
FORCEPROP 2 LAST CDS_LOCATION C9G9
J 1
(-3325 4425);
DISPLAY 0.617021 (-3325 4425);
PAINT AQUA (-3325 4425);
DISPLAY INVISIBLE (-3325 4425);
FORCEPROP 1 LASTPIN (-2975 4425) $PN 1
J 0
(-2985 4440);
DISPLAY 0.787234 (-2985 4440);
PAINT ORANGE (-2985 4440);
DISPLAY INVISIBLE (-2985 4440);
FORCEPROP 2 LAST CDS_LIB mstr_discrete
J 0
(-2875 4425);
PAINT MONO (-2875 4425);
DISPLAY INVISIBLE (-2875 4425);
FORCEPROP 1 LAST VOLTAGE 50V
J 0
(-2800 4425);
DISPLAY 0.617021 (-2800 4425);
PAINT SKYBLUE (-2800 4425);
DISPLAY INVISIBLE (-2800 4425);
FORCEPROP 1 LASTPIN (-2775 4425) $PN 2
J 0
(-2790 4440);
DISPLAY 0.787234 (-2790 4440);
PAINT ORANGE (-2790 4440);
DISPLAY INVISIBLE (-2790 4440);
FORCEPROP 1 LAST PACK_TYPE 0402LF
J 1
(-2625 4425);
DISPLAY 0.617021 (-2625 4425);
PAINT SKYBLUE (-2625 4425);
DISPLAY INVISIBLE (-2625 4425);
FORCEPROP 2 LAST BOM_COST NT_GBE_BASE
J 0
(-2625 4525);
DISPLAY 1.021277 (-2625 4525);
PAINT ORANGE (-2625 4525);
DISPLAY INVISIBLE (-2625 4525);
FORCEPROP 2 LAST ROOM NIC_SPRV
J 0
(-2625 4475);
DISPLAY 1.021277 (-2625 4475);
PAINT ORANGE (-2625 4475);
DISPLAY INVISIBLE (-2625 4475);
FORCEPROP 2 LAST CDS_SEC 1
J 0
(-2875 4675);
PAINT MONO (-2875 4675);
DISPLAY INVISIBLE (-2875 4675);
FORCEPROP 2 LAST $SEC 1
J 0
(-2875 4675);
PAINT MONO (-2875 4675);
DISPLAY INVISIBLE (-2875 4675);
FORCEPROP 2 LAST NO_XNET_CONNECTION 1
J 0
(-2875 4675);
PAINT MONO (-2875 4675);
DISPLAY INVISIBLE (-2875 4675);
FORCEPROP 1 LAST PATH I99
J 0
(-2875 4625);
DISPLAY 0.978723 (-2875 4625);
PAINT WHITE (-2875 4625);
DISPLAY INVISIBLE (-2875 4625);
FORCEADD DESIGN_NOTE..1
(-3800 775);
FORCEPROP 0 LAST L3 ON EMC REQUIREMENTS
J 0
(-4000 525);
DISPLAY 0.808511 (-4000 525);
PAINT ORANGE (-4000 525);
FORCEPROP 0 LAST L2 CAPS (OR REMOVE) DEPENDING
J 0
(-4000 600);
DISPLAY 0.808511 (-4000 600);
PAINT ORANGE (-4000 600);
FORCEPROP 0 LAST L1 CHANGE THESE RESISTORS TO
J 0
(-4000 675);
DISPLAY 0.808511 (-4000 675);
PAINT ORANGE (-4000 675);
FORCEPROP 2 LAST CDS_LIB mstr_symbols
J 0
(-3800 775);
PAINT ORANGE (-3800 775);
DISPLAY INVISIBLE (-3800 775);
FORCEPROP 1 LAST COMMENT_BODY TRUE
J 0
(-3775 875);
DISPLAY 0.978723 (-3775 875);
PAINT ORANGE (-3775 875);
DISPLAY INVISIBLE (-3775 875);
FORCEADD DNS..2
(-3145 4370);
PAINT RED (-3145 4370);
FORCEPROP 1 LAST COMMENT_BODY TRUE
R 1
J 0
(-3070 4145);
DISPLAY 0.872340 (-3070 4145);
PAINT GREEN (-3070 4145);
DISPLAY INVISIBLE (-3070 4145);
FORCEPROP 2 LAST CDS_LIB mstr_misc
J 0
(-3145 4370);
PAINT ORANGE (-3145 4370);
DISPLAY INVISIBLE (-3145 4370);
FORCEADD DNS..2
(-2820 4070);
PAINT RED (-2820 4070);
FORCEPROP 1 LAST COMMENT_BODY TRUE
R 1
J 0
(-2745 3845);
DISPLAY 0.872340 (-2745 3845);
PAINT GREEN (-2745 3845);
DISPLAY INVISIBLE (-2745 3845);
FORCEPROP 2 LAST CDS_LIB mstr_misc
J 0
(-2820 4070);
PAINT ORANGE (-2820 4070);
DISPLAY INVISIBLE (-2820 4070);
FORCEADD DNS..2
(-3095 4020);
PAINT RED (-3095 4020);
FORCEPROP 1 LAST COMMENT_BODY TRUE
R 1
J 0
(-3020 3795);
DISPLAY 0.872340 (-3020 3795);
PAINT GREEN (-3020 3795);
DISPLAY INVISIBLE (-3020 3795);
FORCEPROP 2 LAST CDS_LIB mstr_misc
J 0
(-3095 4020);
PAINT ORANGE (-3095 4020);
DISPLAY INVISIBLE (-3095 4020);
FORCEADD DNS..2
(-2870 4420);
PAINT RED (-2870 4420);
FORCEPROP 1 LAST COMMENT_BODY TRUE
R 1
J 0
(-2795 4195);
DISPLAY 0.872340 (-2795 4195);
PAINT GREEN (-2795 4195);
DISPLAY INVISIBLE (-2795 4195);
FORCEPROP 2 LAST CDS_LIB mstr_misc
J 0
(-2870 4420);
PAINT ORANGE (-2870 4420);
DISPLAY INVISIBLE (-2870 4420);
FORCEADD CAD_NOTE..1
(-3850 1075);
FORCEPROP 0 LAST L1 PLACE THESE RESISTORS ON
J 0
(-4000 950);
DISPLAY 0.808511 (-4000 950);
PAINT ORANGE (-4000 950);
FORCEPROP 0 LAST L2 THE BOTTOM SIDE OF THE BOARD
J 0
(-4000 875);
DISPLAY 0.808511 (-4000 875);
PAINT ORANGE (-4000 875);
FORCEPROP 2 LAST CDS_LIB mstr_symbols
J 0
(-3850 1075);
PAINT ORANGE (-3850 1075);
DISPLAY INVISIBLE (-3850 1075);
FORCEPROP 1 LAST COMMENT_BODY TRUE
J 0
(-3825 1175);
DISPLAY 0.978723 (-3825 1175);
PAINT ORANGE (-3825 1175);
DISPLAY INVISIBLE (-3825 1175);
FORCEADD INTEL_CORP_BPAGE..1
(0 75);
FORCEPROP 1 LAST CDS_CON_LAST_MODIFIED Tue Dec 01 11:52:03 2015
J 0
(-1425 400);
DISPLAY 0.659574 (-1425 400);
PAINT GREEN (-1425 400);
DISPLAY INVISIBLE (-1425 400);
FORCEPROP 1 LAST CUSTOM_TXT_CDS <CURRENT_DESIGN_SHEET> OF <TOTAL_DESIGN_SHEETS>
J 0
(-500 100);
PAINT GREEN (-500 100);
FORCEPROP 2 LAST CUSTOM_TXT_CDS <XR_PAGE_TITLE>
J 0
(-7890 5325);
DISPLAY 0.638298 (-7890 5325);
PAINT PINK (-7890 5325);
DISPLAY INVISIBLE (-7890 5325);
FORCEPROP 2 LAST CUSTOM_TXT_CDS <CON_LAST_MODIFIED>
J 0
(-1925 425);
DISPLAY 0.957447 (-1925 425);
PAINT ORANGE (-1925 425);
FORCEPROP 1 LAST SCH_TITLE LAN SPRINGVILLE I210 (3/3)
J 0
(-7950 125);
DISPLAY 1.212766 (-7950 125);
PAINT GREEN (-7950 125);
FORCEPROP 1 LAST SCH_ADDRESS3 Santa Clara, CA 95052-8119
J 0
(-3975 100);
DISPLAY 0.617021 (-3975 100);
PAINT GREEN (-3975 100);
FORCEPROP 1 LAST SCH_ADDRESS2 P.O. BOX 58119
J 0
(-3975 150);
DISPLAY 0.617021 (-3975 150);
PAINT GREEN (-3975 150);
FORCEPROP 1 LAST SCH_ADDRESS1 2200 Mission College Blvd.
J 0
(-3975 200);
DISPLAY 0.617021 (-3975 200);
PAINT GREEN (-3975 200);
FORCEPROP 1 LAST SCH_NUMBER H4694802
J 0
(-1300 225);
DISPLAY 1.212766 (-1300 225);
PAINT YELLOW (-1300 225);
FORCEPROP 1 LAST SCH_DEPT BESD
J 1
(-4450 175);
DISPLAY 1.212766 (-4450 175);
PAINT YELLOW (-4450 175);
FORCEPROP 1 LAST SCH_REV 2.420
J 0
(-250 225);
DISPLAY 0.978723 (-250 225);
PAINT YELLOW (-250 225);
FORCEPROP 2 LAST PAGE_BORDER TRUE
J 0
(-7890 5325);
DISPLAY 0.425532 (-7890 5325);
PAINT PINK (-7890 5325);
DISPLAY INVISIBLE (-7890 5325);
FORCEPROP 2 LAST CDS_LIB mstr_symbols
J 0
(0 75);
DISPLAY 0.489362 (0 75);
PAINT ORANGE (0 75);
DISPLAY INVISIBLE (0 75);
FORCEPROP 1 LAST COMMENT_BODY TRUE
J 0
(12 87);
DISPLAY 0.319149 (12 87);
PAINT GREEN (12 87);
DISPLAY INVISIBLE (12 87);
FORCEPROP 2 LAST CDS_XR_PAGE_TITLE CR-141 : @BASEBOARD_FAB2_LIB.BASEBOARD_FAB2(SCH_1):PAGE141
J 0
(-7890 5325);
DISPLAY 0.638298 (-7890 5325);
PAINT PINK (-7890 5325);
DISPLAY INVISIBLE (-7890 5325);
WIRE 16 -1 (-4175 2000)(-4025 2000);
WIRE 16 -1 (-4175 1750)(-4175 2000);
FORCEPROP 0 LAST VOLTAGE 0V
J 0
(-4175 1925);
DISPLAY 1.021277 (-4175 1925);
PAINT SKYBLUE (-4175 1925);
DISPLAY INVISIBLE (-4175 1925);
WIRE 16 -1 (-3000 1750)(-3000 2000);
FORCEPROP 0 LAST VOLTAGE 0V
J 0
(-3000 1925);
DISPLAY 1.021277 (-3000 1925);
PAINT SKYBLUE (-3000 1925);
DISPLAY INVISIBLE (-3000 1925);
WIRE 16 -1 (-3000 2000)(-3125 2000);
WIRE 16 -1 (-4175 1350)(-4175 1400);
WIRE 16 -1 (-4175 1400)(-4350 1400);
WIRE 16 -1 (-4700 1400)(-4550 1400);
WIRE 16 -1 (-4700 1350)(-4700 1400);
WIRE 16 -1 (-4175 975)(-4175 1000);
WIRE 16 -1 (-4175 1000)(-4350 1000);
WIRE 16 -1 (-4700 1000)(-4550 1000);
WIRE 16 -1 (-4700 950)(-4700 1000);
WIRE 16 -1 (-5575 1750)(-5575 2050);
WIRE 16 -1 (-1700 750)(-1700 825);
WIRE 16 -1 (-5925 1150)(-5925 1025);
WIRE 16 -1 (-5925 1025)(-6250 1025);
WIRE 16 -1 (-6250 1150)(-6250 1025);
WIRE 16 -1 (-6250 1025)(-6600 1025);
WIRE 16 -1 (-6600 1025)(-6600 1150);
WIRE 16 -1 (-6600 1000)(-6600 1025);
WIRE 16 -1 (-4800 1850)(-4800 1775);
WIRE 16 -1 (-2050 1750)(-2050 1950);
WIRE 16 -1 (-1750 1750)(-1750 1950);
WIRE 16 -1 (-5575 2250)(-5575 2350);
WIRE 16 -1 (-4025 2350)(-5575 2350);
WIRE 16 -1 (-5575 2350)(-5575 2625);
WIRE 16 -1 (-1700 1375)(-1700 1175);
WIRE 16 -1 (-1700 1175)(-1700 1025);
WIRE 16 -1 (-1825 1175)(-1700 1175);
WIRE 16 -1 (-2775 4425)(-2050 4425);
FORCEPROP 2 LAST SIG_NAME NIC_MDI_MNG_RX_DP
J 2
(-2075 4435);
DISPLAY 0.617021 (-2075 4435);
PAINT ORANGE (-2075 4435);
WIRE 16 -1 (-3050 4375)(-2050 4375);
FORCEPROP 2 LAST SIG_NAME NIC_MDI_MNG_RX_DN
J 2
(-2075 4385);
DISPLAY 0.617021 (-2075 4385);
PAINT ORANGE (-2075 4385);
WIRE 16 3135 (-2650 4600)(-3350 4600);
WIRE 16 3135 (-2650 3925)(-2650 4600);
WIRE 16 3135 (-3350 4600)(-3350 3925);
WIRE 16 3135 (-3350 3925)(-2650 3925);
WIRE 16 -1 (-3750 4425)(-2975 4425);
WIRE 16 -1 (-3750 4175)(-3750 4425);
WIRE 16 -1 (-3750 3775)(-3750 4175);
WIRE 16 -1 (-4725 4175)(-3750 4175);
FORCEPROP 2 LAST SIG_NAME NIC_SER_P_MDI_3_DP
J 0
(-4710 4185);
DISPLAY 0.617021 (-4710 4185);
PAINT ORANGE (-4710 4185);
WIRE 16 -1 (-3650 3775)(-3750 3775);
WIRE 16 -1 (-3800 4375)(-3250 4375);
WIRE 16 -1 (-3800 4125)(-3800 4375);
WIRE 16 -1 (-3800 3725)(-3800 4125);
WIRE 16 -1 (-4725 4125)(-3800 4125);
FORCEPROP 2 LAST SIG_NAME NIC_SER_N_MDI_3_DN
J 0
(-4710 4135);
DISPLAY 0.617021 (-4710 4135);
PAINT ORANGE (-4710 4135);
WIRE 16 -1 (-3650 3725)(-3800 3725);
WIRE 16 -1 (-1750 2150)(-1750 2400);
WIRE 16 -1 (-1750 2400)(-1525 2400);
WIRE 16 -1 (-2275 2400)(-1750 2400);
FORCEPROP 2 LAST SIG_NAME LED_LAN_0_N
J 0
(-1835 2410);
DISPLAY 0.617021 (-1835 2410);
PAINT ORANGE (-1835 2410);
WIRE 16 -1 (-2025 1175)(-2600 1175);
WIRE 16 -1 (-2600 2100)(-2600 1175);
WIRE 16 -1 (-3125 2100)(-2600 2100);
FORCEPROP 2 LAST SIG_NAME NIC_LED_ACT_ANODE_R
J 0
(-3025 2110);
DISPLAY 0.617021 (-3025 2110);
PAINT ORANGE (-3025 2110);
FORCEPROP 2 LASTPROP $XRERR UNIQUE?
J 0
(-3265 2110);
DISPLAY 0.638298 (-3265 2110);
PAINT MONO (-3265 2110);
DISPLAY INVISIBLE (-3265 2110);
WIRE 16 -1 (-2050 2150)(-2050 2300);
WIRE 16 -1 (-2050 2300)(-1525 2300);
WIRE 16 -1 (-2450 2300)(-2050 2300);
FORCEPROP 2 LAST SIG_NAME LED_LAN_2_N
J 0
(-1835 2310);
DISPLAY 0.617021 (-1835 2310);
PAINT ORANGE (-1835 2310);
WIRE 16 -1 (-2725 4075)(-2000 4075);
FORCEPROP 2 LAST SIG_NAME NIC_MDI_MNG_TX_DP
J 2
(-2025 4085);
DISPLAY 0.617021 (-2025 4085);
PAINT ORANGE (-2025 4085);
WIRE 16 -1 (-3000 4025)(-2000 4025);
FORCEPROP 2 LAST SIG_NAME NIC_MDI_MNG_TX_DN
J 2
(-2025 4035);
DISPLAY 0.617021 (-2025 4035);
PAINT ORANGE (-2025 4035);
WIRE 16 -1 (-3450 3475)(-2675 3475);
FORCEPROP 2 LAST SIG_NAME NIC_MDI_SPRV_RJ45_0_R_DP
J 0
(-3185 3485);
DISPLAY 0.617021 (-3185 3485);
PAINT ORANGE (-3185 3485);
WIRE 16 -1 (-3125 2800)(-2200 2800);
FORCEPROP 2 LAST SIG_NAME GND_LAN_TRCT1234_C
J 2
(-2200 2810);
DISPLAY 0.617021 (-2200 2810);
PAINT ORANGE (-2200 2810);
WIRE 16 -1 (-3125 2550)(-2200 2550);
FORCEPROP 2 LAST SIG_NAME NIC_MDI_SPRV_RJ45_3_R_DN
J 2
(-2200 2560);
DISPLAY 0.617021 (-2200 2560);
PAINT ORANGE (-2200 2560);
WIRE 16 -1 (-3125 2600)(-2200 2600);
FORCEPROP 2 LAST SIG_NAME GND_LAN_TRCT1234_C
J 2
(-2200 2610);
DISPLAY 0.617021 (-2200 2610);
PAINT ORANGE (-2200 2610);
WIRE 16 -1 (-3125 2650)(-2200 2650);
FORCEPROP 2 LAST SIG_NAME NIC_MDI_SPRV_RJ45_3_R_DP
J 2
(-2200 2660);
DISPLAY 0.617021 (-2200 2660);
PAINT ORANGE (-2200 2660);
WIRE 16 -1 (-3125 2300)(-2650 2300);
FORCEPROP 2 LAST SIG_NAME LED_LAN_2_R_N
J 0
(-3025 2310);
DISPLAY 0.617021 (-3025 2310);
PAINT ORANGE (-3025 2310);
FORCEPROP 2 LASTPROP $XRERR UNIQUE?
J 0
(-3265 2310);
DISPLAY 0.638298 (-3265 2310);
PAINT MONO (-3265 2310);
DISPLAY INVISIBLE (-3265 2310);
WIRE 16 -1 (-3125 2400)(-2475 2400);
FORCEPROP 2 LAST SIG_NAME LED_LAN_0_R_N
J 0
(-3025 2410);
DISPLAY 0.617021 (-3025 2410);
PAINT ORANGE (-3025 2410);
FORCEPROP 2 LASTPROP $XRERR UNIQUE?
J 0
(-3265 2410);
DISPLAY 0.638298 (-3265 2410);
PAINT MONO (-3265 2410);
DISPLAY INVISIBLE (-3265 2410);
WIRE 16 -1 (-3125 2750)(-2200 2750);
FORCEPROP 2 LAST SIG_NAME NIC_MDI_SPRV_RJ45_2_R_DN
J 2
(-2200 2760);
DISPLAY 0.617021 (-2200 2760);
PAINT ORANGE (-2200 2760);
WIRE 16 -1 (-3850 4075)(-2925 4075);
WIRE 16 -1 (-3850 3675)(-3850 4075);
WIRE 16 -1 (-4725 4075)(-3850 4075);
FORCEPROP 2 LAST SIG_NAME NIC_SET_P_MDI_2_DP
J 0
(-4710 4085);
DISPLAY 0.617021 (-4710 4085);
PAINT ORANGE (-4710 4085);
WIRE 16 -1 (-3650 3675)(-3850 3675);
WIRE 16 -1 (-3125 2850)(-2200 2850);
FORCEPROP 2 LAST SIG_NAME NIC_MDI_SPRV_RJ45_2_R_DP
J 2
(-2200 2860);
DISPLAY 0.617021 (-2200 2860);
PAINT ORANGE (-2200 2860);
WIRE 16 -1 (-3450 3775)(-2675 3775);
FORCEPROP 2 LAST SIG_NAME NIC_MDI_SPRV_RJ45_3_R_DP
J 0
(-3185 3785);
DISPLAY 0.617021 (-3185 3785);
PAINT ORANGE (-3185 3785);
WIRE 16 -1 (-3450 3725)(-2675 3725);
FORCEPROP 2 LAST SIG_NAME NIC_MDI_SPRV_RJ45_3_R_DN
J 0
(-3185 3735);
DISPLAY 0.617021 (-3185 3735);
PAINT ORANGE (-3185 3735);
WIRE 16 -1 (-3450 3675)(-2675 3675);
FORCEPROP 2 LAST SIG_NAME NIC_MDI_SPRV_RJ45_2_R_DP
J 0
(-3185 3685);
DISPLAY 0.617021 (-3185 3685);
PAINT ORANGE (-3185 3685);
WIRE 16 -1 (-3450 3625)(-2675 3625);
FORCEPROP 2 LAST SIG_NAME NIC_MDI_SPRV_RJ45_2_R_DN
J 0
(-3185 3635);
DISPLAY 0.617021 (-3185 3635);
PAINT ORANGE (-3185 3635);
WIRE 16 -1 (-3450 3575)(-2675 3575);
FORCEPROP 2 LAST SIG_NAME NIC_MDI_SPRV_RJ45_1_R_DP
J 0
(-3185 3585);
DISPLAY 0.617021 (-3185 3585);
PAINT ORANGE (-3185 3585);
WIRE 16 -1 (-3450 3525)(-2675 3525);
FORCEPROP 2 LAST SIG_NAME NIC_MDI_SPRV_RJ45_1_R_DN
J 0
(-3185 3535);
DISPLAY 0.617021 (-3185 3535);
PAINT ORANGE (-3185 3535);
WIRE 16 -1 (-3450 3425)(-2675 3425);
FORCEPROP 2 LAST SIG_NAME NIC_MDI_SPRV_RJ45_0_R_DN
J 0
(-3185 3435);
DISPLAY 0.617021 (-3185 3435);
PAINT ORANGE (-3185 3435);
WIRE 16 3135 (-3275 3200)(-3275 3825);
WIRE 16 3135 (-3675 3200)(-3275 3200);
WIRE 16 3135 (-3275 3825)(-3675 3825);
WIRE 16 3135 (-3675 3825)(-3675 3200);
WIRE 16 -1 (-3900 4025)(-3200 4025);
WIRE 16 -1 (-3900 3625)(-3900 4025);
WIRE 16 -1 (-3900 4025)(-4725 4025);
FORCEPROP 2 LAST SIG_NAME NIC_SET_N_MDI_2_DN
J 0
(-4710 4035);
DISPLAY 0.617021 (-4710 4035);
PAINT ORANGE (-4710 4035);
WIRE 16 -1 (-3650 3625)(-3900 3625);
WIRE 16 3135 (-2975 475)(-2975 1175);
WIRE 16 3135 (-2975 475)(-4850 475);
WIRE 16 3135 (-2975 1175)(-4025 1175);
WIRE 16 3135 (-4025 1175)(-4025 1575);
WIRE 16 3135 (-4850 1575)(-4850 475);
WIRE 16 3135 (-4025 1575)(-4850 1575);
WIRE 16 -1 (-4325 3475)(-3650 3475);
FORCEPROP 2 LAST SIG_NAME NIC_MDI_SPRV_RJ45_0_DP
J 0
(-4310 3485);
DISPLAY 0.617021 (-4310 3485);
PAINT ORANGE (-4310 3485);
WIRE 16 -1 (-4325 3425)(-3650 3425);
FORCEPROP 2 LAST SIG_NAME NIC_MDI_SPRV_RJ45_0_DN
J 0
(-4310 3435);
DISPLAY 0.617021 (-4310 3435);
PAINT ORANGE (-4310 3435);
WIRE 16 -1 (-4950 2550)(-4025 2550);
FORCEPROP 2 LAST SIG_NAME NIC_MDI_SPRV_RJ45_1_R_DN
J 0
(-4975 2560);
DISPLAY 0.617021 (-4975 2560);
PAINT ORANGE (-4975 2560);
WIRE 16 -1 (-4950 2750)(-4025 2750);
FORCEPROP 2 LAST SIG_NAME NIC_MDI_SPRV_RJ45_0_R_DN
J 0
(-4975 2760);
DISPLAY 0.617021 (-4975 2760);
PAINT ORANGE (-4975 2760);
WIRE 16 -1 (-4950 2850)(-4025 2850);
FORCEPROP 2 LAST SIG_NAME NIC_MDI_SPRV_RJ45_0_R_DP
J 0
(-4975 2860);
DISPLAY 0.617021 (-4975 2860);
PAINT ORANGE (-4975 2860);
WIRE 16 -1 (-4450 2150)(-4025 2150);
FORCEPROP 2 LAST SIG_NAME LED_LAN_1_R_N
J 0
(-4410 2160);
DISPLAY 0.617021 (-4410 2160);
PAINT ORANGE (-4410 2160);
FORCEPROP 2 LASTPROP $XRERR UNIQUE?
J 0
(-4650 2160);
DISPLAY 0.638298 (-4650 2160);
PAINT MONO (-4650 2160);
DISPLAY INVISIBLE (-4650 2160);
WIRE 16 -1 (-4950 2650)(-4025 2650);
FORCEPROP 2 LAST SIG_NAME NIC_MDI_SPRV_RJ45_1_R_DP
J 0
(-4975 2660);
DISPLAY 0.617021 (-4975 2660);
PAINT ORANGE (-4975 2660);
WIRE 16 -1 (-4325 3525)(-3650 3525);
FORCEPROP 2 LAST SIG_NAME NIC_MDI_SPRV_RJ45_1_DN
J 0
(-4310 3535);
DISPLAY 0.617021 (-4310 3535);
PAINT ORANGE (-4310 3535);
WIRE 16 -1 (-4325 3575)(-3650 3575);
FORCEPROP 2 LAST SIG_NAME NIC_MDI_SPRV_RJ45_1_DP
J 0
(-4310 3585);
DISPLAY 0.617021 (-4310 3585);
PAINT ORANGE (-4310 3585);
WIRE 16 -1 (-4950 2800)(-4025 2800);
FORCEPROP 2 LAST SIG_NAME GND_LAN_TRCT1234_C
J 0
(-4975 2810);
DISPLAY 0.617021 (-4975 2810);
PAINT ORANGE (-4975 2810);
WIRE 16 -1 (-4950 2600)(-4025 2600);
FORCEPROP 2 LAST SIG_NAME GND_LAN_TRCT1234_C
J 0
(-4975 2610);
DISPLAY 0.617021 (-4975 2610);
PAINT ORANGE (-4975 2610);
WIRE 16 -1 (-4800 2050)(-4800 2150);
WIRE 16 -1 (-4800 2150)(-4650 2150);
WIRE 16 -1 (-5025 2150)(-4800 2150);
FORCEPROP 2 LAST SIG_NAME LED_LAN_1_N
J 0
(-5050 2160);
DISPLAY 0.617021 (-5050 2160);
PAINT ORANGE (-5050 2160);
WIRE 16 -1 (-5925 1350)(-5925 1500);
WIRE 16 -1 (-5925 1500)(-5400 1500);
FORCEPROP 0 LAST VOLTAGE 0
J 0
(-5650 1550);
DISPLAY 1.021277 (-5650 1550);
PAINT ORANGE (-5650 1550);
DISPLAY INVISIBLE (-5650 1550);
WIRE 16 -1 (-6250 1500)(-5925 1500);
FORCEPROP 2 LAST SIG_NAME GND_LAN_TRCT1234_C
J 0
(-5785 1510);
DISPLAY 0.617021 (-5785 1510);
PAINT ORANGE (-5785 1510);
WIRE 16 -1 (-6250 1350)(-6250 1500);
WIRE 16 -1 (-6600 1500)(-6250 1500);
WIRE 16 -1 (-6600 1350)(-6600 1500);
DOT 1 (-3750 4175);
DOT 1 (-3800 4125);
DOT 1 (-1750 2400);
DOT 1 (-1700 1175);
DOT 1 (-2050 2300);
DOT 1 (-3850 4075);
DOT 1 (-3900 4025);
DOT 1 (-4800 2150);
DOT 1 (-5575 2350);
DOT 1 (-5925 1500);
DOT 1 (-6250 1500);
DOT 1 (-6600 1025);
DOT 1 (-6250 1025);
FORCENOTE
STUFF ON AS
(-3150 4525) 0;
DISPLAY LEFT (-3150 4525);
DISPLAY 0.808511 (-3150 4525);
PAINT PURPLE (-3150 4525);
FORCENOTE
STUFF ON AT
(-3600 3250) 0;
DISPLAY LEFT (-3600 3250);
DISPLAY 0.808511 (-3600 3250);
PAINT PURPLE (-3600 3250);
FORCENOTE
ROOM NT_FABRIC
(-7900 350) 0;
DISPLAY LEFT (-7900 350);
DISPLAY 1.212766 (-7900 350);
PAINT PURPLE (-7900 350);
FORCENOTE
ROOM INTEL_SI
(-7900 450) 0;
DISPLAY LEFT (-7900 450);
DISPLAY 1.212766 (-7900 450);
PAINT PURPLE (-7900 450);
QUIT
